FILE_TYPE = MACRO_DRAWING;
SET COLOR_WIRE YELLOW;
SET COLOR_PROP MONO;
SET COLOR_DOT WHITE;
SET COLOR_ARC YELLOW;
SET COLOR_BODY GREEN;
SET COLOR_NOTE MONO;
SET PROP_DISPLAY VALUE;
SET PAGE_NUMBER P272;
FORCEADD TEST-PAD-12P-1-GP-U..1
(-7600 3425);
FORCEPROP 2 LASTPIN (-7375 3600) $PN 3
J 0
(-7365 3610);
DISPLAY 0.808511 (-7365 3610);
PAINT ORANGE (-7365 3610);
FORCEPROP 2 LASTPIN (-7375 3550) $PN 4
J 0
(-7365 3560);
DISPLAY 0.808511 (-7365 3560);
PAINT ORANGE (-7365 3560);
FORCEPROP 2 LASTPIN (-7375 3500) $PN 5
J 0
(-7365 3510);
DISPLAY 0.808511 (-7365 3510);
PAINT ORANGE (-7365 3510);
FORCEPROP 2 LASTPIN (-7375 3450) $PN 6
J 0
(-7365 3460);
DISPLAY 0.808511 (-7365 3460);
PAINT ORANGE (-7365 3460);
FORCEPROP 2 LASTPIN (-7375 3400) $PN 7
J 0
(-7365 3410);
DISPLAY 0.808511 (-7365 3410);
PAINT ORANGE (-7365 3410);
FORCEPROP 2 LASTPIN (-7375 3350) $PN 8
J 0
(-7365 3360);
DISPLAY 0.808511 (-7365 3360);
PAINT ORANGE (-7365 3360);
FORCEPROP 2 LASTPIN (-7375 3300) $PN 9
J 0
(-7365 3310);
DISPLAY 0.808511 (-7365 3310);
PAINT ORANGE (-7365 3310);
FORCEPROP 2 LASTPIN (-7375 3250) $PN 10
J 0
(-7365 3260);
DISPLAY 0.808511 (-7365 3260);
PAINT ORANGE (-7365 3260);
FORCEPROP 2 LASTPIN (-7375 3200) $PN 11
J 0
(-7365 3210);
DISPLAY 0.808511 (-7365 3210);
PAINT ORANGE (-7365 3210);
FORCEPROP 2 LASTPIN (-7375 3150) $PN 12
J 0
(-7365 3160);
DISPLAY 0.808511 (-7365 3160);
PAINT ORANGE (-7365 3160);
FORCEPROP 2 LASTPIN (-7375 3700) $PN 1
J 0
(-7365 3710);
DISPLAY 0.808511 (-7365 3710);
PAINT ORANGE (-7365 3710);
FORCEPROP 2 LASTPIN (-7375 3650) $PN 2
J 0
(-7365 3660);
DISPLAY 0.808511 (-7365 3660);
PAINT ORANGE (-7365 3660);
FORCEPROP 1 LAST VALUE TEST-PAD-12P-1-GP-U
J 0
(-7675 3000);
DISPLAY 0.617021 (-7675 3000);
PAINT GREEN (-7675 3000);
FORCEPROP 1 LAST LOCATION T1D17
J 0
(-7575 3825);
DISPLAY 0.617021 (-7575 3825);
PAINT GREEN (-7575 3825);
FORCEPROP 2 LAST SEC_TYPE DISCRET-GB1
J 0
(-7575 3875);
DISPLAY 1.021277 (-7575 3875);
PAINT ORANGE (-7575 3875);
DISPLAY INVISIBLE (-7575 3875);
FORCEPROP 2 LAST SEC 1
J 0
(-7575 3875);
DISPLAY 0.680851 (-7575 3875);
PAINT MONO (-7575 3875);
DISPLAY INVISIBLE (-7575 3875);
FORCEPROP 1 LAST PACK_TYPE DISCRET-GB1
J 0
(-7600 3425);
DISPLAY 0.617021 (-7600 3425);
PAINT GREEN (-7600 3425);
DISPLAY INVISIBLE (-7600 3425);
FORCEPROP 1 LAST PART_NUMBER ZZ.00PAD.MJ1
J 0
(-7600 3136);
DISPLAY 0.617021 (-7600 3136);
PAINT GREEN (-7600 3136);
DISPLAY INVISIBLE (-7600 3136);
FORCEPROP 2 LAST CDS_LIB w_hdl
J 0
(-7600 3425);
DISPLAY INVISIBLE (-7600 3425);
FORCEPROP 1 LAST CDS_LMAN_SYM_OUTLINE -75,375,75,-375
J 0
(-7600 3425);
DISPLAY 0.468085 (-7600 3425);
PAINT GREEN (-7600 3425);
DISPLAY INVISIBLE (-7600 3425);
FORCEPROP 1 LAST PATH I1
J 0
(-7600 3715);
DISPLAY 0.617021 (-7600 3715);
PAINT GREEN (-7600 3715);
DISPLAY INVISIBLE (-7600 3715);
FORCEADD GND..1
(-4775 3075);
FORCEPROP 3 LASTPIN (-4775 3125) SIG_NAME GND\g
J 0
(-4765 3135);
DISPLAY 0.659574 (-4765 3135);
PAINT MONO (-4765 3135);
DISPLAY INVISIBLE (-4765 3135);
FORCEPROP 2 LAST CDS_LIB mstr_symbols
J 0
(-4775 3075);
DISPLAY INVISIBLE (-4775 3075);
FORCEPROP 1 LAST SIZE 1B
J 0
(-4700 3025);
DISPLAY 2.382979 (-4700 3025);
PAINT GREEN (-4700 3025);
DISPLAY INVISIBLE (-4700 3025);
FORCEPROP 1 LAST VOLTAGE 0.0V
J 0
(-4820 3032);
DISPLAY 0.340426 (-4820 3032);
PAINT SKYBLUE (-4820 3032);
DISPLAY INVISIBLE (-4820 3032);
FORCEPROP 1 LAST PATH I10
J 0
(-4700 3075);
DISPLAY 0.872340 (-4700 3075);
PAINT AQUA (-4700 3075);
DISPLAY INVISIBLE (-4700 3075);
FORCEPROP 1 LAST BODY_TYPE PLUMBING
J 0
(-4820 3032);
DISPLAY 0.340426 (-4820 3032);
PAINT GREEN (-4820 3032);
DISPLAY INVISIBLE (-4820 3032);
FORCEPROP 1 LAST HDL_POWER GND
J 0
(-4775 3225);
PAINT GREEN (-4775 3225);
DISPLAY INVISIBLE (-4775 3225);
FORCEADD GND..1
(-3925 3075);
FORCEPROP 3 LASTPIN (-3925 3125) SIG_NAME GND\g
J 0
(-3915 3135);
DISPLAY 0.659574 (-3915 3135);
PAINT MONO (-3915 3135);
DISPLAY INVISIBLE (-3915 3135);
FORCEPROP 1 LAST VOLTAGE 0.0V
J 0
(-3970 3032);
DISPLAY 0.340426 (-3970 3032);
PAINT SKYBLUE (-3970 3032);
DISPLAY INVISIBLE (-3970 3032);
FORCEPROP 1 LAST SIZE 1B
J 0
(-3850 3025);
DISPLAY 2.382979 (-3850 3025);
PAINT GREEN (-3850 3025);
DISPLAY INVISIBLE (-3850 3025);
FORCEPROP 2 LAST CDS_LIB mstr_symbols
J 0
(-3925 3075);
DISPLAY INVISIBLE (-3925 3075);
FORCEPROP 1 LAST PATH I11
J 0
(-3850 3075);
DISPLAY 0.872340 (-3850 3075);
PAINT AQUA (-3850 3075);
DISPLAY INVISIBLE (-3850 3075);
FORCEPROP 1 LAST BODY_TYPE PLUMBING
J 0
(-3970 3032);
DISPLAY 0.340426 (-3970 3032);
PAINT GREEN (-3970 3032);
DISPLAY INVISIBLE (-3970 3032);
FORCEPROP 1 LAST HDL_POWER GND
J 0
(-3925 3225);
PAINT GREEN (-3925 3225);
DISPLAY INVISIBLE (-3925 3225);
FORCEADD TEST-PAD-12P-1-GP-U..1
R 2
(-3550 3450);
FORCEPROP 2 LASTPIN (-3775 3625) $PN 3
J 2
(-3785 3635);
DISPLAY 0.808511 (-3785 3635);
PAINT ORANGE (-3785 3635);
FORCEPROP 2 LASTPIN (-3775 3575) $PN 4
J 2
(-3785 3585);
DISPLAY 0.808511 (-3785 3585);
PAINT ORANGE (-3785 3585);
FORCEPROP 2 LASTPIN (-3775 3525) $PN 5
J 2
(-3785 3535);
DISPLAY 0.808511 (-3785 3535);
PAINT ORANGE (-3785 3535);
FORCEPROP 2 LASTPIN (-3775 3475) $PN 6
J 2
(-3785 3485);
DISPLAY 0.808511 (-3785 3485);
PAINT ORANGE (-3785 3485);
FORCEPROP 2 LASTPIN (-3775 3425) $PN 7
J 2
(-3785 3435);
DISPLAY 0.808511 (-3785 3435);
PAINT ORANGE (-3785 3435);
FORCEPROP 2 LASTPIN (-3775 3375) $PN 8
J 2
(-3785 3385);
DISPLAY 0.808511 (-3785 3385);
PAINT ORANGE (-3785 3385);
FORCEPROP 2 LASTPIN (-3775 3325) $PN 9
J 2
(-3785 3335);
DISPLAY 0.808511 (-3785 3335);
PAINT ORANGE (-3785 3335);
FORCEPROP 2 LASTPIN (-3775 3275) $PN 10
J 2
(-3785 3285);
DISPLAY 0.808511 (-3785 3285);
PAINT ORANGE (-3785 3285);
FORCEPROP 2 LASTPIN (-3775 3225) $PN 11
J 2
(-3785 3235);
DISPLAY 0.808511 (-3785 3235);
PAINT ORANGE (-3785 3235);
FORCEPROP 2 LASTPIN (-3775 3175) $PN 12
J 2
(-3785 3185);
DISPLAY 0.808511 (-3785 3185);
PAINT ORANGE (-3785 3185);
FORCEPROP 2 LASTPIN (-3775 3725) $PN 1
J 2
(-3785 3735);
DISPLAY 0.808511 (-3785 3735);
PAINT ORANGE (-3785 3735);
FORCEPROP 2 LASTPIN (-3775 3675) $PN 2
J 2
(-3785 3685);
DISPLAY 0.808511 (-3785 3685);
PAINT ORANGE (-3785 3685);
FORCEPROP 1 LAST VALUE TEST-PAD-12P-1-GP-U
J 2
(-3475 3025);
DISPLAY 0.617021 (-3475 3025);
PAINT GREEN (-3475 3025);
FORCEPROP 1 LAST LOCATION T1D24
J 2
(-3575 3850);
DISPLAY 0.617021 (-3575 3850);
PAINT GREEN (-3575 3850);
FORCEPROP 2 LAST SEC_TYPE DISCRET-GB1
J 2
(-3575 3900);
DISPLAY 1.021277 (-3575 3900);
PAINT ORANGE (-3575 3900);
DISPLAY INVISIBLE (-3575 3900);
FORCEPROP 2 LAST SEC 1
J 2
(-3575 3900);
DISPLAY 0.680851 (-3575 3900);
PAINT MONO (-3575 3900);
DISPLAY INVISIBLE (-3575 3900);
FORCEPROP 1 LAST PACK_TYPE DISCRET-GB1
J 2
(-3550 3450);
DISPLAY 0.617021 (-3550 3450);
PAINT GREEN (-3550 3450);
DISPLAY INVISIBLE (-3550 3450);
FORCEPROP 1 LAST PART_NUMBER ZZ.00PAD.MJ1
J 2
(-3550 3161);
DISPLAY 0.617021 (-3550 3161);
PAINT GREEN (-3550 3161);
DISPLAY INVISIBLE (-3550 3161);
FORCEPROP 2 LAST CDS_LIB w_hdl
J 2
(-3550 3450);
DISPLAY INVISIBLE (-3550 3450);
FORCEPROP 1 LAST CDS_LMAN_SYM_OUTLINE -75,375,75,-375
J 2
(-3550 3450);
DISPLAY 0.468085 (-3550 3450);
PAINT GREEN (-3550 3450);
DISPLAY INVISIBLE (-3550 3450);
FORCEPROP 1 LAST PATH I12
J 2
(-3550 3740);
DISPLAY 0.617021 (-3550 3740);
PAINT GREEN (-3550 3740);
DISPLAY INVISIBLE (-3550 3740);
FORCEADD GND..1
(-6375 4000);
FORCEPROP 3 LASTPIN (-6375 4050) SIG_NAME GND\g
J 0
(-6365 4060);
DISPLAY 0.659574 (-6365 4060);
PAINT MONO (-6365 4060);
DISPLAY INVISIBLE (-6365 4060);
FORCEPROP 1 LAST VOLTAGE 0.0V
J 0
(-6420 3957);
DISPLAY 0.340426 (-6420 3957);
PAINT SKYBLUE (-6420 3957);
DISPLAY INVISIBLE (-6420 3957);
FORCEPROP 1 LAST SIZE 1B
J 0
(-6300 3950);
DISPLAY 2.382979 (-6300 3950);
PAINT GREEN (-6300 3950);
DISPLAY INVISIBLE (-6300 3950);
FORCEPROP 2 LAST CDS_LIB mstr_symbols
J 0
(-6375 4000);
DISPLAY INVISIBLE (-6375 4000);
FORCEPROP 1 LAST PATH I13
J 0
(-6300 4000);
DISPLAY 0.872340 (-6300 4000);
PAINT AQUA (-6300 4000);
DISPLAY INVISIBLE (-6300 4000);
FORCEPROP 1 LAST BODY_TYPE PLUMBING
J 0
(-6420 3957);
DISPLAY 0.340426 (-6420 3957);
PAINT GREEN (-6420 3957);
DISPLAY INVISIBLE (-6420 3957);
FORCEPROP 1 LAST HDL_POWER GND
J 0
(-6375 4150);
PAINT GREEN (-6375 4150);
DISPLAY INVISIBLE (-6375 4150);
FORCEADD TEST-PAD-12P-1-GP-U..1
R 2
(-6000 4375);
FORCEPROP 2 LASTPIN (-6225 4550) $PN 3
J 2
(-6235 4560);
DISPLAY 0.808511 (-6235 4560);
PAINT ORANGE (-6235 4560);
FORCEPROP 2 LASTPIN (-6225 4500) $PN 4
J 2
(-6235 4510);
DISPLAY 0.808511 (-6235 4510);
PAINT ORANGE (-6235 4510);
FORCEPROP 2 LASTPIN (-6225 4450) $PN 5
J 2
(-6235 4460);
DISPLAY 0.808511 (-6235 4460);
PAINT ORANGE (-6235 4460);
FORCEPROP 2 LASTPIN (-6225 4400) $PN 6
J 2
(-6235 4410);
DISPLAY 0.808511 (-6235 4410);
PAINT ORANGE (-6235 4410);
FORCEPROP 2 LASTPIN (-6225 4350) $PN 7
J 2
(-6235 4360);
DISPLAY 0.808511 (-6235 4360);
PAINT ORANGE (-6235 4360);
FORCEPROP 2 LASTPIN (-6225 4300) $PN 8
J 2
(-6235 4310);
DISPLAY 0.808511 (-6235 4310);
PAINT ORANGE (-6235 4310);
FORCEPROP 2 LASTPIN (-6225 4250) $PN 9
J 2
(-6235 4260);
DISPLAY 0.808511 (-6235 4260);
PAINT ORANGE (-6235 4260);
FORCEPROP 2 LASTPIN (-6225 4200) $PN 10
J 2
(-6235 4210);
DISPLAY 0.808511 (-6235 4210);
PAINT ORANGE (-6235 4210);
FORCEPROP 2 LASTPIN (-6225 4150) $PN 11
J 2
(-6235 4160);
DISPLAY 0.808511 (-6235 4160);
PAINT ORANGE (-6235 4160);
FORCEPROP 2 LASTPIN (-6225 4100) $PN 12
J 2
(-6235 4110);
DISPLAY 0.808511 (-6235 4110);
PAINT ORANGE (-6235 4110);
FORCEPROP 2 LASTPIN (-6225 4650) $PN 1
J 2
(-6235 4660);
DISPLAY 0.808511 (-6235 4660);
PAINT ORANGE (-6235 4660);
FORCEPROP 2 LASTPIN (-6225 4600) $PN 2
J 2
(-6235 4610);
DISPLAY 0.808511 (-6235 4610);
PAINT ORANGE (-6235 4610);
FORCEPROP 1 LAST VALUE TEST-PAD-12P-1-GP-U
J 2
(-5925 3950);
DISPLAY 0.617021 (-5925 3950);
PAINT GREEN (-5925 3950);
FORCEPROP 1 LAST LOCATION T1D16
J 2
(-6025 4775);
DISPLAY 0.617021 (-6025 4775);
PAINT GREEN (-6025 4775);
FORCEPROP 2 LAST SEC_TYPE DISCRET-GB1
J 2
(-6025 4825);
DISPLAY 1.021277 (-6025 4825);
PAINT ORANGE (-6025 4825);
DISPLAY INVISIBLE (-6025 4825);
FORCEPROP 2 LAST SEC 1
J 2
(-6025 4825);
DISPLAY 0.680851 (-6025 4825);
PAINT MONO (-6025 4825);
DISPLAY INVISIBLE (-6025 4825);
FORCEPROP 1 LAST PACK_TYPE DISCRET-GB1
J 2
(-6000 4375);
DISPLAY 0.617021 (-6000 4375);
PAINT GREEN (-6000 4375);
DISPLAY INVISIBLE (-6000 4375);
FORCEPROP 1 LAST PART_NUMBER ZZ.00PAD.MJ1
J 2
(-6000 4086);
DISPLAY 0.617021 (-6000 4086);
PAINT GREEN (-6000 4086);
DISPLAY INVISIBLE (-6000 4086);
FORCEPROP 2 LAST CDS_LIB w_hdl
J 2
(-6000 4375);
DISPLAY INVISIBLE (-6000 4375);
FORCEPROP 1 LAST CDS_LMAN_SYM_OUTLINE -75,375,75,-375
J 2
(-6000 4375);
DISPLAY 0.468085 (-6000 4375);
PAINT GREEN (-6000 4375);
DISPLAY INVISIBLE (-6000 4375);
FORCEPROP 1 LAST PATH I14
J 2
(-6000 4665);
DISPLAY 0.617021 (-6000 4665);
PAINT GREEN (-6000 4665);
DISPLAY INVISIBLE (-6000 4665);
FORCEADD GND..1
(-6375 4950);
FORCEPROP 3 LASTPIN (-6375 5000) SIG_NAME GND\g
J 0
(-6365 5010);
DISPLAY 0.659574 (-6365 5010);
PAINT MONO (-6365 5010);
DISPLAY INVISIBLE (-6365 5010);
FORCEPROP 2 LAST CDS_LIB mstr_symbols
J 0
(-6375 4950);
DISPLAY INVISIBLE (-6375 4950);
FORCEPROP 1 LAST SIZE 1B
J 0
(-6300 4900);
DISPLAY 2.382979 (-6300 4900);
PAINT GREEN (-6300 4900);
DISPLAY INVISIBLE (-6300 4900);
FORCEPROP 1 LAST VOLTAGE 0.0V
J 0
(-6420 4907);
DISPLAY 0.340426 (-6420 4907);
PAINT SKYBLUE (-6420 4907);
DISPLAY INVISIBLE (-6420 4907);
FORCEPROP 1 LAST PATH I15
J 0
(-6300 4950);
DISPLAY 0.872340 (-6300 4950);
PAINT AQUA (-6300 4950);
DISPLAY INVISIBLE (-6300 4950);
FORCEPROP 1 LAST BODY_TYPE PLUMBING
J 0
(-6420 4907);
DISPLAY 0.340426 (-6420 4907);
PAINT GREEN (-6420 4907);
DISPLAY INVISIBLE (-6420 4907);
FORCEPROP 1 LAST HDL_POWER GND
J 0
(-6375 5100);
PAINT GREEN (-6375 5100);
DISPLAY INVISIBLE (-6375 5100);
FORCEADD TEST-PAD-12P-1-GP-U..1
(-5150 4400);
FORCEPROP 2 LASTPIN (-4925 4575) $PN 3
J 0
(-4915 4585);
DISPLAY 0.808511 (-4915 4585);
PAINT ORANGE (-4915 4585);
FORCEPROP 2 LASTPIN (-4925 4525) $PN 4
J 0
(-4915 4535);
DISPLAY 0.808511 (-4915 4535);
PAINT ORANGE (-4915 4535);
FORCEPROP 2 LASTPIN (-4925 4475) $PN 5
J 0
(-4915 4485);
DISPLAY 0.808511 (-4915 4485);
PAINT ORANGE (-4915 4485);
FORCEPROP 2 LASTPIN (-4925 4425) $PN 6
J 0
(-4915 4435);
DISPLAY 0.808511 (-4915 4435);
PAINT ORANGE (-4915 4435);
FORCEPROP 2 LASTPIN (-4925 4375) $PN 7
J 0
(-4915 4385);
DISPLAY 0.808511 (-4915 4385);
PAINT ORANGE (-4915 4385);
FORCEPROP 2 LASTPIN (-4925 4275) $PN 9
J 0
(-4915 4285);
DISPLAY 0.808511 (-4915 4285);
PAINT ORANGE (-4915 4285);
FORCEPROP 2 LASTPIN (-4925 4225) $PN 10
J 0
(-4915 4235);
DISPLAY 0.808511 (-4915 4235);
PAINT ORANGE (-4915 4235);
FORCEPROP 2 LASTPIN (-4925 4175) $PN 11
J 0
(-4915 4185);
DISPLAY 0.808511 (-4915 4185);
PAINT ORANGE (-4915 4185);
FORCEPROP 2 LASTPIN (-4925 4125) $PN 12
J 0
(-4915 4135);
DISPLAY 0.808511 (-4915 4135);
PAINT ORANGE (-4915 4135);
FORCEPROP 2 LASTPIN (-4925 4675) $PN 1
J 0
(-4915 4685);
DISPLAY 0.808511 (-4915 4685);
PAINT ORANGE (-4915 4685);
FORCEPROP 2 LASTPIN (-4925 4625) $PN 2
J 0
(-4915 4635);
DISPLAY 0.808511 (-4915 4635);
PAINT ORANGE (-4915 4635);
FORCEPROP 1 LAST VALUE TEST-PAD-12P-1-GP-U
J 0
(-5225 3975);
DISPLAY 0.617021 (-5225 3975);
PAINT GREEN (-5225 3975);
FORCEPROP 2 LASTPIN (-4925 4325) $PN 8
J 0
(-4915 4335);
DISPLAY 0.808511 (-4915 4335);
PAINT ORANGE (-4915 4335);
FORCEPROP 1 LAST LOCATION T1D21
J 0
(-5125 4800);
DISPLAY 0.617021 (-5125 4800);
PAINT GREEN (-5125 4800);
FORCEPROP 2 LAST SEC_TYPE DISCRET-GB1
J 0
(-5125 4850);
DISPLAY 1.021277 (-5125 4850);
PAINT ORANGE (-5125 4850);
DISPLAY INVISIBLE (-5125 4850);
FORCEPROP 2 LAST SEC 1
J 0
(-5125 4850);
DISPLAY 0.680851 (-5125 4850);
PAINT MONO (-5125 4850);
DISPLAY INVISIBLE (-5125 4850);
FORCEPROP 1 LAST PACK_TYPE DISCRET-GB1
J 0
(-5150 4400);
DISPLAY 0.617021 (-5150 4400);
PAINT GREEN (-5150 4400);
DISPLAY INVISIBLE (-5150 4400);
FORCEPROP 1 LAST PART_NUMBER ZZ.00PAD.MJ1
J 0
(-5150 4111);
DISPLAY 0.617021 (-5150 4111);
PAINT GREEN (-5150 4111);
DISPLAY INVISIBLE (-5150 4111);
FORCEPROP 2 LAST CDS_LIB w_hdl
J 0
(-5150 4400);
DISPLAY INVISIBLE (-5150 4400);
FORCEPROP 1 LAST CDS_LMAN_SYM_OUTLINE -75,375,75,-375
J 0
(-5150 4400);
DISPLAY 0.468085 (-5150 4400);
PAINT GREEN (-5150 4400);
DISPLAY INVISIBLE (-5150 4400);
FORCEPROP 1 LAST PATH I16
J 0
(-5150 4690);
DISPLAY 0.617021 (-5150 4690);
PAINT GREEN (-5150 4690);
DISPLAY INVISIBLE (-5150 4690);
FORCEADD GND..1
(-4775 4025);
FORCEPROP 3 LASTPIN (-4775 4075) SIG_NAME GND\g
J 0
(-4765 4085);
DISPLAY 0.659574 (-4765 4085);
PAINT MONO (-4765 4085);
DISPLAY INVISIBLE (-4765 4085);
FORCEPROP 2 LAST CDS_LIB mstr_symbols
J 0
(-4775 4025);
DISPLAY INVISIBLE (-4775 4025);
FORCEPROP 1 LAST SIZE 1B
J 0
(-4700 3975);
DISPLAY 2.382979 (-4700 3975);
PAINT GREEN (-4700 3975);
DISPLAY INVISIBLE (-4700 3975);
FORCEPROP 1 LAST VOLTAGE 0.0V
J 0
(-4820 3982);
DISPLAY 0.340426 (-4820 3982);
PAINT SKYBLUE (-4820 3982);
DISPLAY INVISIBLE (-4820 3982);
FORCEPROP 1 LAST PATH I17
J 0
(-4700 4025);
DISPLAY 0.872340 (-4700 4025);
PAINT AQUA (-4700 4025);
DISPLAY INVISIBLE (-4700 4025);
FORCEPROP 1 LAST BODY_TYPE PLUMBING
J 0
(-4820 3982);
DISPLAY 0.340426 (-4820 3982);
PAINT GREEN (-4820 3982);
DISPLAY INVISIBLE (-4820 3982);
FORCEPROP 1 LAST HDL_POWER GND
J 0
(-4775 4175);
PAINT GREEN (-4775 4175);
DISPLAY INVISIBLE (-4775 4175);
FORCEADD GND..1
(-3925 4025);
FORCEPROP 3 LASTPIN (-3925 4075) SIG_NAME GND\g
J 0
(-3915 4085);
DISPLAY 0.659574 (-3915 4085);
PAINT MONO (-3915 4085);
DISPLAY INVISIBLE (-3915 4085);
FORCEPROP 1 LAST VOLTAGE 0.0V
J 0
(-3970 3982);
DISPLAY 0.340426 (-3970 3982);
PAINT SKYBLUE (-3970 3982);
DISPLAY INVISIBLE (-3970 3982);
FORCEPROP 1 LAST SIZE 1B
J 0
(-3850 3975);
DISPLAY 2.382979 (-3850 3975);
PAINT GREEN (-3850 3975);
DISPLAY INVISIBLE (-3850 3975);
FORCEPROP 2 LAST CDS_LIB mstr_symbols
J 0
(-3925 4025);
DISPLAY INVISIBLE (-3925 4025);
FORCEPROP 1 LAST PATH I18
J 0
(-3850 4025);
DISPLAY 0.872340 (-3850 4025);
PAINT AQUA (-3850 4025);
DISPLAY INVISIBLE (-3850 4025);
FORCEPROP 1 LAST BODY_TYPE PLUMBING
J 0
(-3970 3982);
DISPLAY 0.340426 (-3970 3982);
PAINT GREEN (-3970 3982);
DISPLAY INVISIBLE (-3970 3982);
FORCEPROP 1 LAST HDL_POWER GND
J 0
(-3925 4175);
PAINT GREEN (-3925 4175);
DISPLAY INVISIBLE (-3925 4175);
FORCEADD GND..1
(-4775 4975);
FORCEPROP 3 LASTPIN (-4775 5025) SIG_NAME GND\g
J 0
(-4765 5035);
DISPLAY 0.659574 (-4765 5035);
PAINT MONO (-4765 5035);
DISPLAY INVISIBLE (-4765 5035);
FORCEPROP 2 LAST CDS_LIB mstr_symbols
J 0
(-4775 4975);
DISPLAY INVISIBLE (-4775 4975);
FORCEPROP 1 LAST SIZE 1B
J 0
(-4700 4925);
DISPLAY 2.382979 (-4700 4925);
PAINT GREEN (-4700 4925);
DISPLAY INVISIBLE (-4700 4925);
FORCEPROP 1 LAST VOLTAGE 0.0V
J 0
(-4820 4932);
DISPLAY 0.340426 (-4820 4932);
PAINT SKYBLUE (-4820 4932);
DISPLAY INVISIBLE (-4820 4932);
FORCEPROP 1 LAST PATH I19
J 0
(-4700 4975);
DISPLAY 0.872340 (-4700 4975);
PAINT AQUA (-4700 4975);
DISPLAY INVISIBLE (-4700 4975);
FORCEPROP 1 LAST BODY_TYPE PLUMBING
J 0
(-4820 4932);
DISPLAY 0.340426 (-4820 4932);
PAINT GREEN (-4820 4932);
DISPLAY INVISIBLE (-4820 4932);
FORCEPROP 1 LAST HDL_POWER GND
J 0
(-4775 5125);
PAINT GREEN (-4775 5125);
DISPLAY INVISIBLE (-4775 5125);
FORCEADD GND..1
(-7225 3050);
FORCEPROP 3 LASTPIN (-7225 3100) SIG_NAME GND\g
J 0
(-7215 3110);
DISPLAY 0.659574 (-7215 3110);
PAINT MONO (-7215 3110);
DISPLAY INVISIBLE (-7215 3110);
FORCEPROP 2 LAST CDS_LIB mstr_symbols
J 0
(-7225 3050);
DISPLAY INVISIBLE (-7225 3050);
FORCEPROP 1 LAST SIZE 1B
J 0
(-7150 3000);
DISPLAY 2.382979 (-7150 3000);
PAINT GREEN (-7150 3000);
DISPLAY INVISIBLE (-7150 3000);
FORCEPROP 1 LAST VOLTAGE 0.0V
J 0
(-7270 3007);
DISPLAY 0.340426 (-7270 3007);
PAINT SKYBLUE (-7270 3007);
DISPLAY INVISIBLE (-7270 3007);
FORCEPROP 1 LAST PATH I2
J 0
(-7150 3050);
DISPLAY 0.872340 (-7150 3050);
PAINT AQUA (-7150 3050);
DISPLAY INVISIBLE (-7150 3050);
FORCEPROP 1 LAST BODY_TYPE PLUMBING
J 0
(-7270 3007);
DISPLAY 0.340426 (-7270 3007);
PAINT GREEN (-7270 3007);
DISPLAY INVISIBLE (-7270 3007);
FORCEPROP 1 LAST HDL_POWER GND
J 0
(-7225 3200);
PAINT GREEN (-7225 3200);
DISPLAY INVISIBLE (-7225 3200);
FORCEADD GND..1
(-3925 4975);
FORCEPROP 3 LASTPIN (-3925 5025) SIG_NAME GND\g
J 0
(-3915 5035);
DISPLAY 0.659574 (-3915 5035);
PAINT MONO (-3915 5035);
DISPLAY INVISIBLE (-3915 5035);
FORCEPROP 1 LAST VOLTAGE 0.0V
J 0
(-3970 4932);
DISPLAY 0.340426 (-3970 4932);
PAINT SKYBLUE (-3970 4932);
DISPLAY INVISIBLE (-3970 4932);
FORCEPROP 1 LAST SIZE 1B
J 0
(-3850 4925);
DISPLAY 2.382979 (-3850 4925);
PAINT GREEN (-3850 4925);
DISPLAY INVISIBLE (-3850 4925);
FORCEPROP 2 LAST CDS_LIB mstr_symbols
J 0
(-3925 4975);
DISPLAY INVISIBLE (-3925 4975);
FORCEPROP 1 LAST PATH I20
J 0
(-3850 4975);
DISPLAY 0.872340 (-3850 4975);
PAINT AQUA (-3850 4975);
DISPLAY INVISIBLE (-3850 4975);
FORCEPROP 1 LAST BODY_TYPE PLUMBING
J 0
(-3970 4932);
DISPLAY 0.340426 (-3970 4932);
PAINT GREEN (-3970 4932);
DISPLAY INVISIBLE (-3970 4932);
FORCEPROP 1 LAST HDL_POWER GND
J 0
(-3925 5125);
PAINT GREEN (-3925 5125);
DISPLAY INVISIBLE (-3925 5125);
FORCEADD TEST-PAD-12P-1-GP-U..1
R 2
(-3550 4400);
FORCEPROP 2 LASTPIN (-3775 4575) $PN 3
J 2
(-3785 4585);
DISPLAY 0.808511 (-3785 4585);
PAINT ORANGE (-3785 4585);
FORCEPROP 2 LASTPIN (-3775 4525) $PN 4
J 2
(-3785 4535);
DISPLAY 0.808511 (-3785 4535);
PAINT ORANGE (-3785 4535);
FORCEPROP 2 LASTPIN (-3775 4475) $PN 5
J 2
(-3785 4485);
DISPLAY 0.808511 (-3785 4485);
PAINT ORANGE (-3785 4485);
FORCEPROP 2 LASTPIN (-3775 4425) $PN 6
J 2
(-3785 4435);
DISPLAY 0.808511 (-3785 4435);
PAINT ORANGE (-3785 4435);
FORCEPROP 2 LASTPIN (-3775 4375) $PN 7
J 2
(-3785 4385);
DISPLAY 0.808511 (-3785 4385);
PAINT ORANGE (-3785 4385);
FORCEPROP 2 LASTPIN (-3775 4325) $PN 8
J 2
(-3785 4335);
DISPLAY 0.808511 (-3785 4335);
PAINT ORANGE (-3785 4335);
FORCEPROP 2 LASTPIN (-3775 4275) $PN 9
J 2
(-3785 4285);
DISPLAY 0.808511 (-3785 4285);
PAINT ORANGE (-3785 4285);
FORCEPROP 2 LASTPIN (-3775 4225) $PN 10
J 2
(-3785 4235);
DISPLAY 0.808511 (-3785 4235);
PAINT ORANGE (-3785 4235);
FORCEPROP 2 LASTPIN (-3775 4175) $PN 11
J 2
(-3785 4185);
DISPLAY 0.808511 (-3785 4185);
PAINT ORANGE (-3785 4185);
FORCEPROP 2 LASTPIN (-3775 4125) $PN 12
J 2
(-3785 4135);
DISPLAY 0.808511 (-3785 4135);
PAINT ORANGE (-3785 4135);
FORCEPROP 2 LASTPIN (-3775 4675) $PN 1
J 2
(-3785 4685);
DISPLAY 0.808511 (-3785 4685);
PAINT ORANGE (-3785 4685);
FORCEPROP 2 LASTPIN (-3775 4625) $PN 2
J 2
(-3785 4635);
DISPLAY 0.808511 (-3785 4635);
PAINT ORANGE (-3785 4635);
FORCEPROP 1 LAST VALUE TEST-PAD-12P-1-GP-U
J 2
(-3475 3975);
DISPLAY 0.617021 (-3475 3975);
PAINT GREEN (-3475 3975);
FORCEPROP 1 LAST LOCATION T1D22
J 2
(-3575 4800);
DISPLAY 0.617021 (-3575 4800);
PAINT GREEN (-3575 4800);
FORCEPROP 2 LAST SEC_TYPE DISCRET-GB1
J 2
(-3575 4850);
DISPLAY 1.021277 (-3575 4850);
PAINT ORANGE (-3575 4850);
DISPLAY INVISIBLE (-3575 4850);
FORCEPROP 2 LAST SEC 1
J 2
(-3575 4850);
DISPLAY 0.680851 (-3575 4850);
PAINT MONO (-3575 4850);
DISPLAY INVISIBLE (-3575 4850);
FORCEPROP 1 LAST PACK_TYPE DISCRET-GB1
J 2
(-3550 4400);
DISPLAY 0.617021 (-3550 4400);
PAINT GREEN (-3550 4400);
DISPLAY INVISIBLE (-3550 4400);
FORCEPROP 1 LAST PART_NUMBER ZZ.00PAD.MJ1
J 2
(-3550 4111);
DISPLAY 0.617021 (-3550 4111);
PAINT GREEN (-3550 4111);
DISPLAY INVISIBLE (-3550 4111);
FORCEPROP 2 LAST CDS_LIB w_hdl
J 2
(-3550 4400);
DISPLAY INVISIBLE (-3550 4400);
FORCEPROP 1 LAST CDS_LMAN_SYM_OUTLINE -75,375,75,-375
J 2
(-3550 4400);
DISPLAY 0.468085 (-3550 4400);
PAINT GREEN (-3550 4400);
DISPLAY INVISIBLE (-3550 4400);
FORCEPROP 1 LAST PATH I21
J 2
(-3550 4690);
DISPLAY 0.617021 (-3550 4690);
PAINT GREEN (-3550 4690);
DISPLAY INVISIBLE (-3550 4690);
FORCEADD TEST-PAD-12P-1-GP-U..1
R 2
(-6000 5325);
FORCEPROP 2 LASTPIN (-6225 5550) $PN 2
J 2
(-6235 5560);
DISPLAY 0.808511 (-6235 5560);
PAINT ORANGE (-6235 5560);
FORCEPROP 2 LASTPIN (-6225 5600) $PN 1
J 2
(-6235 5610);
DISPLAY 0.808511 (-6235 5610);
PAINT ORANGE (-6235 5610);
FORCEPROP 2 LASTPIN (-6225 5050) $PN 12
J 2
(-6235 5060);
DISPLAY 0.808511 (-6235 5060);
PAINT ORANGE (-6235 5060);
FORCEPROP 2 LASTPIN (-6225 5100) $PN 11
J 2
(-6235 5110);
DISPLAY 0.808511 (-6235 5110);
PAINT ORANGE (-6235 5110);
FORCEPROP 2 LASTPIN (-6225 5150) $PN 10
J 2
(-6235 5160);
DISPLAY 0.808511 (-6235 5160);
PAINT ORANGE (-6235 5160);
FORCEPROP 2 LASTPIN (-6225 5200) $PN 9
J 2
(-6235 5210);
DISPLAY 0.808511 (-6235 5210);
PAINT ORANGE (-6235 5210);
FORCEPROP 2 LASTPIN (-6225 5250) $PN 8
J 2
(-6235 5260);
DISPLAY 0.808511 (-6235 5260);
PAINT ORANGE (-6235 5260);
FORCEPROP 2 LASTPIN (-6225 5300) $PN 7
J 2
(-6235 5310);
DISPLAY 0.808511 (-6235 5310);
PAINT ORANGE (-6235 5310);
FORCEPROP 2 LASTPIN (-6225 5350) $PN 6
J 2
(-6235 5360);
DISPLAY 0.808511 (-6235 5360);
PAINT ORANGE (-6235 5360);
FORCEPROP 2 LASTPIN (-6225 5400) $PN 5
J 2
(-6235 5410);
DISPLAY 0.808511 (-6235 5410);
PAINT ORANGE (-6235 5410);
FORCEPROP 2 LASTPIN (-6225 5500) $PN 3
J 2
(-6235 5510);
DISPLAY 0.808511 (-6235 5510);
PAINT ORANGE (-6235 5510);
FORCEPROP 1 LAST VALUE TEST-PAD-12P-1-GP-U
J 2
(-5925 4900);
DISPLAY 0.617021 (-5925 4900);
PAINT GREEN (-5925 4900);
FORCEPROP 1 LAST LOCATION T1D14
J 2
(-6025 5725);
DISPLAY 0.617021 (-6025 5725);
PAINT GREEN (-6025 5725);
FORCEPROP 2 LASTPIN (-6225 5450) $PN 4
J 2
(-6235 5460);
DISPLAY 0.808511 (-6235 5460);
PAINT ORANGE (-6235 5460);
FORCEPROP 1 LAST CDS_LMAN_SYM_OUTLINE -75,375,75,-375
J 2
(-6000 5325);
DISPLAY 0.468085 (-6000 5325);
PAINT GREEN (-6000 5325);
DISPLAY INVISIBLE (-6000 5325);
FORCEPROP 2 LAST CDS_LIB w_hdl
J 2
(-6000 5325);
DISPLAY INVISIBLE (-6000 5325);
FORCEPROP 1 LAST PART_NUMBER ZZ.00PAD.MJ1
J 2
(-6000 5036);
DISPLAY 0.617021 (-6000 5036);
PAINT GREEN (-6000 5036);
DISPLAY INVISIBLE (-6000 5036);
FORCEPROP 1 LAST PACK_TYPE DISCRET-GB1
J 2
(-6000 5325);
DISPLAY 0.617021 (-6000 5325);
PAINT GREEN (-6000 5325);
DISPLAY INVISIBLE (-6000 5325);
FORCEPROP 2 LAST SEC 1
J 2
(-6025 5775);
DISPLAY 0.680851 (-6025 5775);
PAINT MONO (-6025 5775);
DISPLAY INVISIBLE (-6025 5775);
FORCEPROP 2 LAST SEC_TYPE DISCRET-GB1
J 2
(-6025 5775);
DISPLAY 1.021277 (-6025 5775);
PAINT ORANGE (-6025 5775);
DISPLAY INVISIBLE (-6025 5775);
FORCEPROP 1 LAST PATH I22
J 2
(-6000 5615);
DISPLAY 0.617021 (-6000 5615);
PAINT GREEN (-6000 5615);
DISPLAY INVISIBLE (-6000 5615);
FORCEADD TEST-PAD-12P-1-GP-U..1
(-5150 5350);
FORCEPROP 2 LASTPIN (-4925 5525) $PN 3
J 0
(-4915 5535);
DISPLAY 0.808511 (-4915 5535);
PAINT ORANGE (-4915 5535);
FORCEPROP 2 LASTPIN (-4925 5475) $PN 4
J 0
(-4915 5485);
DISPLAY 0.808511 (-4915 5485);
PAINT ORANGE (-4915 5485);
FORCEPROP 2 LASTPIN (-4925 5425) $PN 5
J 0
(-4915 5435);
DISPLAY 0.808511 (-4915 5435);
PAINT ORANGE (-4915 5435);
FORCEPROP 2 LASTPIN (-4925 5375) $PN 6
J 0
(-4915 5385);
DISPLAY 0.808511 (-4915 5385);
PAINT ORANGE (-4915 5385);
FORCEPROP 2 LASTPIN (-4925 5325) $PN 7
J 0
(-4915 5335);
DISPLAY 0.808511 (-4915 5335);
PAINT ORANGE (-4915 5335);
FORCEPROP 2 LASTPIN (-4925 5275) $PN 8
J 0
(-4915 5285);
DISPLAY 0.808511 (-4915 5285);
PAINT ORANGE (-4915 5285);
FORCEPROP 2 LASTPIN (-4925 5225) $PN 9
J 0
(-4915 5235);
DISPLAY 0.808511 (-4915 5235);
PAINT ORANGE (-4915 5235);
FORCEPROP 2 LASTPIN (-4925 5175) $PN 10
J 0
(-4915 5185);
DISPLAY 0.808511 (-4915 5185);
PAINT ORANGE (-4915 5185);
FORCEPROP 2 LASTPIN (-4925 5125) $PN 11
J 0
(-4915 5135);
DISPLAY 0.808511 (-4915 5135);
PAINT ORANGE (-4915 5135);
FORCEPROP 2 LASTPIN (-4925 5075) $PN 12
J 0
(-4915 5085);
DISPLAY 0.808511 (-4915 5085);
PAINT ORANGE (-4915 5085);
FORCEPROP 2 LASTPIN (-4925 5625) $PN 1
J 0
(-4915 5635);
DISPLAY 0.808511 (-4915 5635);
PAINT ORANGE (-4915 5635);
FORCEPROP 2 LASTPIN (-4925 5575) $PN 2
J 0
(-4915 5585);
DISPLAY 0.808511 (-4915 5585);
PAINT ORANGE (-4915 5585);
FORCEPROP 1 LAST VALUE TEST-PAD-12P-1-GP-U
J 0
(-5225 4925);
DISPLAY 0.617021 (-5225 4925);
PAINT GREEN (-5225 4925);
FORCEPROP 1 LAST LOCATION T1D19
J 0
(-5125 5750);
DISPLAY 0.617021 (-5125 5750);
PAINT GREEN (-5125 5750);
FORCEPROP 2 LAST SEC_TYPE DISCRET-GB1
J 0
(-5125 5800);
DISPLAY 1.021277 (-5125 5800);
PAINT ORANGE (-5125 5800);
DISPLAY INVISIBLE (-5125 5800);
FORCEPROP 2 LAST SEC 1
J 0
(-5125 5800);
DISPLAY 0.680851 (-5125 5800);
PAINT MONO (-5125 5800);
DISPLAY INVISIBLE (-5125 5800);
FORCEPROP 1 LAST PACK_TYPE DISCRET-GB1
J 0
(-5150 5350);
DISPLAY 0.617021 (-5150 5350);
PAINT GREEN (-5150 5350);
DISPLAY INVISIBLE (-5150 5350);
FORCEPROP 1 LAST PART_NUMBER ZZ.00PAD.MJ1
J 0
(-5150 5061);
DISPLAY 0.617021 (-5150 5061);
PAINT GREEN (-5150 5061);
DISPLAY INVISIBLE (-5150 5061);
FORCEPROP 2 LAST CDS_LIB w_hdl
J 0
(-5150 5350);
DISPLAY INVISIBLE (-5150 5350);
FORCEPROP 1 LAST CDS_LMAN_SYM_OUTLINE -75,375,75,-375
J 0
(-5150 5350);
DISPLAY 0.468085 (-5150 5350);
PAINT GREEN (-5150 5350);
DISPLAY INVISIBLE (-5150 5350);
FORCEPROP 1 LAST PATH I23
J 0
(-5150 5640);
DISPLAY 0.617021 (-5150 5640);
PAINT GREEN (-5150 5640);
DISPLAY INVISIBLE (-5150 5640);
FORCEADD TEST-PAD-12P-1-GP-U..1
R 2
(-3550 5350);
FORCEPROP 2 LASTPIN (-3775 5525) $PN 3
J 2
(-3785 5535);
DISPLAY 0.808511 (-3785 5535);
PAINT ORANGE (-3785 5535);
FORCEPROP 2 LASTPIN (-3775 5475) $PN 4
J 2
(-3785 5485);
DISPLAY 0.808511 (-3785 5485);
PAINT ORANGE (-3785 5485);
FORCEPROP 2 LASTPIN (-3775 5425) $PN 5
J 2
(-3785 5435);
DISPLAY 0.808511 (-3785 5435);
PAINT ORANGE (-3785 5435);
FORCEPROP 2 LASTPIN (-3775 5375) $PN 6
J 2
(-3785 5385);
DISPLAY 0.808511 (-3785 5385);
PAINT ORANGE (-3785 5385);
FORCEPROP 2 LASTPIN (-3775 5325) $PN 7
J 2
(-3785 5335);
DISPLAY 0.808511 (-3785 5335);
PAINT ORANGE (-3785 5335);
FORCEPROP 2 LASTPIN (-3775 5275) $PN 8
J 2
(-3785 5285);
DISPLAY 0.808511 (-3785 5285);
PAINT ORANGE (-3785 5285);
FORCEPROP 2 LASTPIN (-3775 5225) $PN 9
J 2
(-3785 5235);
DISPLAY 0.808511 (-3785 5235);
PAINT ORANGE (-3785 5235);
FORCEPROP 2 LASTPIN (-3775 5175) $PN 10
J 2
(-3785 5185);
DISPLAY 0.808511 (-3785 5185);
PAINT ORANGE (-3785 5185);
FORCEPROP 2 LASTPIN (-3775 5125) $PN 11
J 2
(-3785 5135);
DISPLAY 0.808511 (-3785 5135);
PAINT ORANGE (-3785 5135);
FORCEPROP 2 LASTPIN (-3775 5075) $PN 12
J 2
(-3785 5085);
DISPLAY 0.808511 (-3785 5085);
PAINT ORANGE (-3785 5085);
FORCEPROP 2 LASTPIN (-3775 5625) $PN 1
J 2
(-3785 5635);
DISPLAY 0.808511 (-3785 5635);
PAINT ORANGE (-3785 5635);
FORCEPROP 2 LASTPIN (-3775 5575) $PN 2
J 2
(-3785 5585);
DISPLAY 0.808511 (-3785 5585);
PAINT ORANGE (-3785 5585);
FORCEPROP 1 LAST VALUE TEST-PAD-12P-1-GP-U
J 2
(-3475 4925);
DISPLAY 0.617021 (-3475 4925);
PAINT GREEN (-3475 4925);
FORCEPROP 1 LAST LOCATION T1D20
J 2
(-3575 5750);
DISPLAY 0.617021 (-3575 5750);
PAINT GREEN (-3575 5750);
FORCEPROP 2 LAST SEC_TYPE DISCRET-GB1
J 2
(-3575 5800);
DISPLAY 1.021277 (-3575 5800);
PAINT ORANGE (-3575 5800);
DISPLAY INVISIBLE (-3575 5800);
FORCEPROP 2 LAST SEC 1
J 2
(-3575 5800);
DISPLAY 0.680851 (-3575 5800);
PAINT MONO (-3575 5800);
DISPLAY INVISIBLE (-3575 5800);
FORCEPROP 1 LAST PACK_TYPE DISCRET-GB1
J 2
(-3550 5350);
DISPLAY 0.617021 (-3550 5350);
PAINT GREEN (-3550 5350);
DISPLAY INVISIBLE (-3550 5350);
FORCEPROP 1 LAST PART_NUMBER ZZ.00PAD.MJ1
J 2
(-3550 5061);
DISPLAY 0.617021 (-3550 5061);
PAINT GREEN (-3550 5061);
DISPLAY INVISIBLE (-3550 5061);
FORCEPROP 2 LAST CDS_LIB w_hdl
J 2
(-3550 5350);
DISPLAY INVISIBLE (-3550 5350);
FORCEPROP 1 LAST CDS_LMAN_SYM_OUTLINE -75,375,75,-375
J 2
(-3550 5350);
DISPLAY 0.468085 (-3550 5350);
PAINT GREEN (-3550 5350);
DISPLAY INVISIBLE (-3550 5350);
FORCEPROP 1 LAST PATH I24
J 2
(-3550 5640);
DISPLAY 0.617021 (-3550 5640);
PAINT GREEN (-3550 5640);
DISPLAY INVISIBLE (-3550 5640);
FORCEADD TEST-PAD-12P-1-GP-U..1
(-7600 4375);
FORCEPROP 2 LASTPIN (-7375 4550) $PN 3
J 0
(-7365 4560);
DISPLAY 0.808511 (-7365 4560);
PAINT ORANGE (-7365 4560);
FORCEPROP 2 LASTPIN (-7375 4500) $PN 4
J 0
(-7365 4510);
DISPLAY 0.808511 (-7365 4510);
PAINT ORANGE (-7365 4510);
FORCEPROP 2 LASTPIN (-7375 4450) $PN 5
J 0
(-7365 4460);
DISPLAY 0.808511 (-7365 4460);
PAINT ORANGE (-7365 4460);
FORCEPROP 2 LASTPIN (-7375 4400) $PN 6
J 0
(-7365 4410);
DISPLAY 0.808511 (-7365 4410);
PAINT ORANGE (-7365 4410);
FORCEPROP 2 LASTPIN (-7375 4350) $PN 7
J 0
(-7365 4360);
DISPLAY 0.808511 (-7365 4360);
PAINT ORANGE (-7365 4360);
FORCEPROP 2 LASTPIN (-7375 4300) $PN 8
J 0
(-7365 4310);
DISPLAY 0.808511 (-7365 4310);
PAINT ORANGE (-7365 4310);
FORCEPROP 2 LASTPIN (-7375 4250) $PN 9
J 0
(-7365 4260);
DISPLAY 0.808511 (-7365 4260);
PAINT ORANGE (-7365 4260);
FORCEPROP 2 LASTPIN (-7375 4200) $PN 10
J 0
(-7365 4210);
DISPLAY 0.808511 (-7365 4210);
PAINT ORANGE (-7365 4210);
FORCEPROP 2 LASTPIN (-7375 4150) $PN 11
J 0
(-7365 4160);
DISPLAY 0.808511 (-7365 4160);
PAINT ORANGE (-7365 4160);
FORCEPROP 2 LASTPIN (-7375 4100) $PN 12
J 0
(-7365 4110);
DISPLAY 0.808511 (-7365 4110);
PAINT ORANGE (-7365 4110);
FORCEPROP 2 LASTPIN (-7375 4650) $PN 1
J 0
(-7365 4660);
DISPLAY 0.808511 (-7365 4660);
PAINT ORANGE (-7365 4660);
FORCEPROP 2 LASTPIN (-7375 4600) $PN 2
J 0
(-7365 4610);
DISPLAY 0.808511 (-7365 4610);
PAINT ORANGE (-7365 4610);
FORCEPROP 1 LAST VALUE TEST-PAD-12P-1-GP-U
J 0
(-7675 3950);
DISPLAY 0.617021 (-7675 3950);
PAINT GREEN (-7675 3950);
FORCEPROP 1 LAST LOCATION T1D15
J 0
(-7575 4775);
DISPLAY 0.617021 (-7575 4775);
PAINT GREEN (-7575 4775);
FORCEPROP 2 LAST SEC_TYPE DISCRET-GB1
J 0
(-7575 4825);
DISPLAY 1.021277 (-7575 4825);
PAINT ORANGE (-7575 4825);
DISPLAY INVISIBLE (-7575 4825);
FORCEPROP 2 LAST SEC 1
J 0
(-7575 4825);
DISPLAY 0.680851 (-7575 4825);
PAINT MONO (-7575 4825);
DISPLAY INVISIBLE (-7575 4825);
FORCEPROP 1 LAST PACK_TYPE DISCRET-GB1
J 0
(-7600 4375);
DISPLAY 0.617021 (-7600 4375);
PAINT GREEN (-7600 4375);
DISPLAY INVISIBLE (-7600 4375);
FORCEPROP 1 LAST PART_NUMBER ZZ.00PAD.MJ1
J 0
(-7600 4086);
DISPLAY 0.617021 (-7600 4086);
PAINT GREEN (-7600 4086);
DISPLAY INVISIBLE (-7600 4086);
FORCEPROP 2 LAST CDS_LIB w_hdl
J 0
(-7600 4375);
DISPLAY INVISIBLE (-7600 4375);
FORCEPROP 1 LAST CDS_LMAN_SYM_OUTLINE -75,375,75,-375
J 0
(-7600 4375);
DISPLAY 0.468085 (-7600 4375);
PAINT GREEN (-7600 4375);
DISPLAY INVISIBLE (-7600 4375);
FORCEPROP 1 LAST PATH I3
J 0
(-7600 4665);
DISPLAY 0.617021 (-7600 4665);
PAINT GREEN (-7600 4665);
DISPLAY INVISIBLE (-7600 4665);
FORCEADD GND..1
(-7225 4000);
FORCEPROP 3 LASTPIN (-7225 4050) SIG_NAME GND\g
J 0
(-7215 4060);
DISPLAY 0.659574 (-7215 4060);
PAINT MONO (-7215 4060);
DISPLAY INVISIBLE (-7215 4060);
FORCEPROP 2 LAST CDS_LIB mstr_symbols
J 0
(-7225 4000);
DISPLAY INVISIBLE (-7225 4000);
FORCEPROP 1 LAST SIZE 1B
J 0
(-7150 3950);
DISPLAY 2.382979 (-7150 3950);
PAINT GREEN (-7150 3950);
DISPLAY INVISIBLE (-7150 3950);
FORCEPROP 1 LAST VOLTAGE 0.0V
J 0
(-7270 3957);
DISPLAY 0.340426 (-7270 3957);
PAINT SKYBLUE (-7270 3957);
DISPLAY INVISIBLE (-7270 3957);
FORCEPROP 1 LAST PATH I4
J 0
(-7150 4000);
DISPLAY 0.872340 (-7150 4000);
PAINT AQUA (-7150 4000);
DISPLAY INVISIBLE (-7150 4000);
FORCEPROP 1 LAST BODY_TYPE PLUMBING
J 0
(-7270 3957);
DISPLAY 0.340426 (-7270 3957);
PAINT GREEN (-7270 3957);
DISPLAY INVISIBLE (-7270 3957);
FORCEPROP 1 LAST HDL_POWER GND
J 0
(-7225 4150);
PAINT GREEN (-7225 4150);
DISPLAY INVISIBLE (-7225 4150);
FORCEADD TEST-PAD-12P-1-GP-U..1
(-7600 5325);
FORCEPROP 1 LAST VALUE TEST-PAD-12P-1-GP-U
J 0
(-7675 4900);
DISPLAY 0.617021 (-7675 4900);
PAINT GREEN (-7675 4900);
FORCEPROP 2 LASTPIN (-7375 5550) $PN 2
J 0
(-7365 5560);
DISPLAY 0.808511 (-7365 5560);
PAINT ORANGE (-7365 5560);
FORCEPROP 2 LASTPIN (-7375 5600) $PN 1
J 0
(-7365 5610);
DISPLAY 0.808511 (-7365 5610);
PAINT ORANGE (-7365 5610);
FORCEPROP 2 LASTPIN (-7375 5050) $PN 12
J 0
(-7365 5060);
DISPLAY 0.808511 (-7365 5060);
PAINT ORANGE (-7365 5060);
FORCEPROP 2 LASTPIN (-7375 5100) $PN 11
J 0
(-7365 5110);
DISPLAY 0.808511 (-7365 5110);
PAINT ORANGE (-7365 5110);
FORCEPROP 2 LASTPIN (-7375 5150) $PN 10
J 0
(-7365 5160);
DISPLAY 0.808511 (-7365 5160);
PAINT ORANGE (-7365 5160);
FORCEPROP 2 LASTPIN (-7375 5200) $PN 9
J 0
(-7365 5210);
DISPLAY 0.808511 (-7365 5210);
PAINT ORANGE (-7365 5210);
FORCEPROP 2 LASTPIN (-7375 5250) $PN 8
J 0
(-7365 5260);
DISPLAY 0.808511 (-7365 5260);
PAINT ORANGE (-7365 5260);
FORCEPROP 2 LASTPIN (-7375 5300) $PN 7
J 0
(-7365 5310);
DISPLAY 0.808511 (-7365 5310);
PAINT ORANGE (-7365 5310);
FORCEPROP 2 LASTPIN (-7375 5350) $PN 6
J 0
(-7365 5360);
DISPLAY 0.808511 (-7365 5360);
PAINT ORANGE (-7365 5360);
FORCEPROP 2 LASTPIN (-7375 5400) $PN 5
J 0
(-7365 5410);
DISPLAY 0.808511 (-7365 5410);
PAINT ORANGE (-7365 5410);
FORCEPROP 2 LASTPIN (-7375 5450) $PN 4
J 0
(-7365 5460);
DISPLAY 0.808511 (-7365 5460);
PAINT ORANGE (-7365 5460);
FORCEPROP 2 LASTPIN (-7375 5500) $PN 3
J 0
(-7365 5510);
DISPLAY 0.808511 (-7365 5510);
PAINT ORANGE (-7365 5510);
FORCEPROP 1 LAST LOCATION T1D13
J 0
(-7575 5725);
DISPLAY 0.617021 (-7575 5725);
PAINT GREEN (-7575 5725);
FORCEPROP 1 LAST CDS_LMAN_SYM_OUTLINE -75,375,75,-375
J 0
(-7600 5325);
DISPLAY 0.468085 (-7600 5325);
PAINT GREEN (-7600 5325);
DISPLAY INVISIBLE (-7600 5325);
FORCEPROP 2 LAST CDS_LIB w_hdl
J 0
(-7600 5325);
DISPLAY INVISIBLE (-7600 5325);
FORCEPROP 1 LAST PART_NUMBER ZZ.00PAD.MJ1
J 0
(-7600 5036);
DISPLAY 0.617021 (-7600 5036);
PAINT GREEN (-7600 5036);
DISPLAY INVISIBLE (-7600 5036);
FORCEPROP 1 LAST PACK_TYPE DISCRET-GB1
J 0
(-7600 5325);
DISPLAY 0.617021 (-7600 5325);
PAINT GREEN (-7600 5325);
DISPLAY INVISIBLE (-7600 5325);
FORCEPROP 2 LAST SEC 1
J 0
(-7575 5775);
DISPLAY 0.680851 (-7575 5775);
PAINT MONO (-7575 5775);
DISPLAY INVISIBLE (-7575 5775);
FORCEPROP 2 LAST SEC_TYPE DISCRET-GB1
J 0
(-7575 5775);
DISPLAY 1.021277 (-7575 5775);
PAINT ORANGE (-7575 5775);
DISPLAY INVISIBLE (-7575 5775);
FORCEPROP 1 LAST PATH I5
J 0
(-7600 5615);
DISPLAY 0.617021 (-7600 5615);
PAINT GREEN (-7600 5615);
DISPLAY INVISIBLE (-7600 5615);
FORCEADD GND..1
(-7225 4950);
FORCEPROP 3 LASTPIN (-7225 5000) SIG_NAME GND\g
J 0
(-7215 5010);
DISPLAY 0.659574 (-7215 5010);
PAINT MONO (-7215 5010);
DISPLAY INVISIBLE (-7215 5010);
FORCEPROP 1 LAST VOLTAGE 0.0V
J 0
(-7270 4907);
DISPLAY 0.340426 (-7270 4907);
PAINT SKYBLUE (-7270 4907);
DISPLAY INVISIBLE (-7270 4907);
FORCEPROP 1 LAST SIZE 1B
J 0
(-7150 4900);
DISPLAY 2.382979 (-7150 4900);
PAINT GREEN (-7150 4900);
DISPLAY INVISIBLE (-7150 4900);
FORCEPROP 2 LAST CDS_LIB mstr_symbols
J 0
(-7225 4950);
DISPLAY INVISIBLE (-7225 4950);
FORCEPROP 1 LAST PATH I6
J 0
(-7150 4950);
DISPLAY 0.872340 (-7150 4950);
PAINT AQUA (-7150 4950);
DISPLAY INVISIBLE (-7150 4950);
FORCEPROP 1 LAST BODY_TYPE PLUMBING
J 0
(-7270 4907);
DISPLAY 0.340426 (-7270 4907);
PAINT GREEN (-7270 4907);
DISPLAY INVISIBLE (-7270 4907);
FORCEPROP 1 LAST HDL_POWER GND
J 0
(-7225 5100);
PAINT GREEN (-7225 5100);
DISPLAY INVISIBLE (-7225 5100);
FORCEADD GND..1
(-6375 3050);
FORCEPROP 3 LASTPIN (-6375 3100) SIG_NAME GND\g
J 0
(-6365 3110);
DISPLAY 0.659574 (-6365 3110);
PAINT MONO (-6365 3110);
DISPLAY INVISIBLE (-6365 3110);
FORCEPROP 1 LAST VOLTAGE 0.0V
J 0
(-6420 3007);
DISPLAY 0.340426 (-6420 3007);
PAINT SKYBLUE (-6420 3007);
DISPLAY INVISIBLE (-6420 3007);
FORCEPROP 1 LAST SIZE 1B
J 0
(-6300 3000);
DISPLAY 2.382979 (-6300 3000);
PAINT GREEN (-6300 3000);
DISPLAY INVISIBLE (-6300 3000);
FORCEPROP 2 LAST CDS_LIB mstr_symbols
J 0
(-6375 3050);
DISPLAY INVISIBLE (-6375 3050);
FORCEPROP 1 LAST PATH I7
J 0
(-6300 3050);
DISPLAY 0.872340 (-6300 3050);
PAINT AQUA (-6300 3050);
DISPLAY INVISIBLE (-6300 3050);
FORCEPROP 1 LAST BODY_TYPE PLUMBING
J 0
(-6420 3007);
DISPLAY 0.340426 (-6420 3007);
PAINT GREEN (-6420 3007);
DISPLAY INVISIBLE (-6420 3007);
FORCEPROP 1 LAST HDL_POWER GND
J 0
(-6375 3200);
PAINT GREEN (-6375 3200);
DISPLAY INVISIBLE (-6375 3200);
FORCEADD TEST-PAD-12P-1-GP-U..1
R 2
(-6000 3425);
FORCEPROP 2 LASTPIN (-6225 3600) $PN 3
J 2
(-6235 3610);
DISPLAY 0.808511 (-6235 3610);
PAINT ORANGE (-6235 3610);
FORCEPROP 2 LASTPIN (-6225 3550) $PN 4
J 2
(-6235 3560);
DISPLAY 0.808511 (-6235 3560);
PAINT ORANGE (-6235 3560);
FORCEPROP 2 LASTPIN (-6225 3500) $PN 5
J 2
(-6235 3510);
DISPLAY 0.808511 (-6235 3510);
PAINT ORANGE (-6235 3510);
FORCEPROP 2 LASTPIN (-6225 3450) $PN 6
J 2
(-6235 3460);
DISPLAY 0.808511 (-6235 3460);
PAINT ORANGE (-6235 3460);
FORCEPROP 2 LASTPIN (-6225 3400) $PN 7
J 2
(-6235 3410);
DISPLAY 0.808511 (-6235 3410);
PAINT ORANGE (-6235 3410);
FORCEPROP 2 LASTPIN (-6225 3350) $PN 8
J 2
(-6235 3360);
DISPLAY 0.808511 (-6235 3360);
PAINT ORANGE (-6235 3360);
FORCEPROP 2 LASTPIN (-6225 3300) $PN 9
J 2
(-6235 3310);
DISPLAY 0.808511 (-6235 3310);
PAINT ORANGE (-6235 3310);
FORCEPROP 2 LASTPIN (-6225 3250) $PN 10
J 2
(-6235 3260);
DISPLAY 0.808511 (-6235 3260);
PAINT ORANGE (-6235 3260);
FORCEPROP 2 LASTPIN (-6225 3200) $PN 11
J 2
(-6235 3210);
DISPLAY 0.808511 (-6235 3210);
PAINT ORANGE (-6235 3210);
FORCEPROP 2 LASTPIN (-6225 3150) $PN 12
J 2
(-6235 3160);
DISPLAY 0.808511 (-6235 3160);
PAINT ORANGE (-6235 3160);
FORCEPROP 2 LASTPIN (-6225 3700) $PN 1
J 2
(-6235 3710);
DISPLAY 0.808511 (-6235 3710);
PAINT ORANGE (-6235 3710);
FORCEPROP 2 LASTPIN (-6225 3650) $PN 2
J 2
(-6235 3660);
DISPLAY 0.808511 (-6235 3660);
PAINT ORANGE (-6235 3660);
FORCEPROP 1 LAST VALUE TEST-PAD-12P-1-GP-U
J 2
(-5925 3000);
DISPLAY 0.617021 (-5925 3000);
PAINT GREEN (-5925 3000);
FORCEPROP 1 LAST LOCATION T1D18
J 2
(-6025 3825);
DISPLAY 0.617021 (-6025 3825);
PAINT GREEN (-6025 3825);
FORCEPROP 2 LAST SEC_TYPE DISCRET-GB1
J 2
(-6025 3875);
DISPLAY 1.021277 (-6025 3875);
PAINT ORANGE (-6025 3875);
DISPLAY INVISIBLE (-6025 3875);
FORCEPROP 2 LAST SEC 1
J 2
(-6025 3875);
DISPLAY 0.680851 (-6025 3875);
PAINT MONO (-6025 3875);
DISPLAY INVISIBLE (-6025 3875);
FORCEPROP 1 LAST PACK_TYPE DISCRET-GB1
J 2
(-6000 3425);
DISPLAY 0.617021 (-6000 3425);
PAINT GREEN (-6000 3425);
DISPLAY INVISIBLE (-6000 3425);
FORCEPROP 1 LAST PART_NUMBER ZZ.00PAD.MJ1
J 2
(-6000 3136);
DISPLAY 0.617021 (-6000 3136);
PAINT GREEN (-6000 3136);
DISPLAY INVISIBLE (-6000 3136);
FORCEPROP 2 LAST CDS_LIB w_hdl
J 2
(-6000 3425);
DISPLAY INVISIBLE (-6000 3425);
FORCEPROP 1 LAST CDS_LMAN_SYM_OUTLINE -75,375,75,-375
J 2
(-6000 3425);
DISPLAY 0.468085 (-6000 3425);
PAINT GREEN (-6000 3425);
DISPLAY INVISIBLE (-6000 3425);
FORCEPROP 1 LAST PATH I8
J 2
(-6000 3715);
DISPLAY 0.617021 (-6000 3715);
PAINT GREEN (-6000 3715);
DISPLAY INVISIBLE (-6000 3715);
FORCEADD TEST-PAD-12P-1-GP-U..1
(-5150 3450);
FORCEPROP 2 LASTPIN (-4925 3625) $PN 3
J 0
(-4915 3635);
DISPLAY 0.808511 (-4915 3635);
PAINT ORANGE (-4915 3635);
FORCEPROP 2 LASTPIN (-4925 3575) $PN 4
J 0
(-4915 3585);
DISPLAY 0.808511 (-4915 3585);
PAINT ORANGE (-4915 3585);
FORCEPROP 2 LASTPIN (-4925 3525) $PN 5
J 0
(-4915 3535);
DISPLAY 0.808511 (-4915 3535);
PAINT ORANGE (-4915 3535);
FORCEPROP 2 LASTPIN (-4925 3475) $PN 6
J 0
(-4915 3485);
DISPLAY 0.808511 (-4915 3485);
PAINT ORANGE (-4915 3485);
FORCEPROP 2 LASTPIN (-4925 3425) $PN 7
J 0
(-4915 3435);
DISPLAY 0.808511 (-4915 3435);
PAINT ORANGE (-4915 3435);
FORCEPROP 2 LASTPIN (-4925 3375) $PN 8
J 0
(-4915 3385);
DISPLAY 0.808511 (-4915 3385);
PAINT ORANGE (-4915 3385);
FORCEPROP 2 LASTPIN (-4925 3325) $PN 9
J 0
(-4915 3335);
DISPLAY 0.808511 (-4915 3335);
PAINT ORANGE (-4915 3335);
FORCEPROP 2 LASTPIN (-4925 3275) $PN 10
J 0
(-4915 3285);
DISPLAY 0.808511 (-4915 3285);
PAINT ORANGE (-4915 3285);
FORCEPROP 2 LASTPIN (-4925 3225) $PN 11
J 0
(-4915 3235);
DISPLAY 0.808511 (-4915 3235);
PAINT ORANGE (-4915 3235);
FORCEPROP 2 LASTPIN (-4925 3175) $PN 12
J 0
(-4915 3185);
DISPLAY 0.808511 (-4915 3185);
PAINT ORANGE (-4915 3185);
FORCEPROP 2 LASTPIN (-4925 3725) $PN 1
J 0
(-4915 3735);
DISPLAY 0.808511 (-4915 3735);
PAINT ORANGE (-4915 3735);
FORCEPROP 2 LASTPIN (-4925 3675) $PN 2
J 0
(-4915 3685);
DISPLAY 0.808511 (-4915 3685);
PAINT ORANGE (-4915 3685);
FORCEPROP 1 LAST VALUE TEST-PAD-12P-1-GP-U
J 0
(-5225 3025);
DISPLAY 0.617021 (-5225 3025);
PAINT GREEN (-5225 3025);
FORCEPROP 1 LAST LOCATION T1D23
J 0
(-5125 3850);
DISPLAY 0.617021 (-5125 3850);
PAINT GREEN (-5125 3850);
FORCEPROP 2 LAST SEC_TYPE DISCRET-GB1
J 0
(-5125 3900);
DISPLAY 1.021277 (-5125 3900);
PAINT ORANGE (-5125 3900);
DISPLAY INVISIBLE (-5125 3900);
FORCEPROP 2 LAST SEC 1
J 0
(-5125 3900);
DISPLAY 0.680851 (-5125 3900);
PAINT MONO (-5125 3900);
DISPLAY INVISIBLE (-5125 3900);
FORCEPROP 1 LAST PACK_TYPE DISCRET-GB1
J 0
(-5150 3450);
DISPLAY 0.617021 (-5150 3450);
PAINT GREEN (-5150 3450);
DISPLAY INVISIBLE (-5150 3450);
FORCEPROP 1 LAST PART_NUMBER ZZ.00PAD.MJ1
J 0
(-5150 3161);
DISPLAY 0.617021 (-5150 3161);
PAINT GREEN (-5150 3161);
DISPLAY INVISIBLE (-5150 3161);
FORCEPROP 2 LAST CDS_LIB w_hdl
J 0
(-5150 3450);
DISPLAY INVISIBLE (-5150 3450);
FORCEPROP 1 LAST CDS_LMAN_SYM_OUTLINE -75,375,75,-375
J 0
(-5150 3450);
DISPLAY 0.468085 (-5150 3450);
PAINT GREEN (-5150 3450);
DISPLAY INVISIBLE (-5150 3450);
FORCEPROP 1 LAST PATH I9
J 0
(-5150 3740);
DISPLAY 0.617021 (-5150 3740);
PAINT GREEN (-5150 3740);
DISPLAY INVISIBLE (-5150 3740);
FORCEADD INTEL_CORP_BPAGE..1
(-1225 1550);
FORCEPROP 1 LAST CDS_CON_LAST_MODIFIED Fri Jun 16 17:49:34 2017
J 0
(-2650 1875);
PAINT ORANGE (-2650 1875);
DISPLAY INVISIBLE (-2650 1875);
FORCEPROP 1 LAST CUSTOM_TXT_CDS <CURRENT_DESIGN_SHEET> OF <TOTAL_DESIGN_SHEETS>
J 0
(-1725 1575);
PAINT ORANGE (-1725 1575);
FORCEPROP 1 LAST CUSTOM_TXT_CDS <CON_LAST_MODIFIED>
J 0
(-5225 1650);
PAINT ORANGE (-5225 1650);
FORCEPROP 2 LAST CUSTOM_TXT_CDS <XR_PAGE_TITLE>
J 0
(-9115 6800);
DISPLAY 0.638298 (-9115 6800);
PAINT PINK (-9115 6800);
DISPLAY INVISIBLE (-9115 6800);
FORCEPROP 2 LAST CUSTOM_TXT_CDS 257 OF 270
J 0
(-1725 1575);
PAINT ORANGE (-1725 1575);
FORCEPROP 2 LAST CUSTOM_TXT_CDS Thu Nov 17 16:16:25 2016
J 0
(-5225 1650);
PAINT ORANGE (-5225 1650);
FORCEPROP 1 LAST SCH_TITLE COUPON - 3 OF 3
J 0
(-9175 1600);
DISPLAY 2.468085 (-9175 1600);
PAINT ORANGE (-9175 1600);
FORCEPROP 2 LAST CDS_LIB mstr_symbols
J 0
(-1225 1550);
DISPLAY INVISIBLE (-1225 1550);
FORCEPROP 2 LAST PAGE_BORDER TRUE
J 0
(-9115 6800);
DISPLAY 0.638298 (-9115 6800);
PAINT PINK (-9115 6800);
DISPLAY INVISIBLE (-9115 6800);
FORCEPROP 1 LAST COMMENT_BODY TRUE
J 0
(-1213 1562);
DISPLAY 0.468085 (-1213 1562);
PAINT GREEN (-1213 1562);
DISPLAY INVISIBLE (-1213 1562);
FORCEPROP 2 LAST CDS_XR_PAGE_TITLE CR-258 : @BASEBOARD_FAB2_LIB.BASEBOARD_FAB2(SCH_1):PAGE258
J 0
(-9115 6800);
DISPLAY 0.638298 (-9115 6800);
PAINT PINK (-9115 6800);
DISPLAY INVISIBLE (-9115 6800);
WIRE 16 -1 (-4775 3125)(-4775 3175);
WIRE 16 -1 (-4775 3225)(-4775 3175);
WIRE 16 -1 (-4925 3175)(-4775 3175);
WIRE 16 -1 (-4775 3275)(-4775 3225);
WIRE 16 -1 (-4925 3225)(-4775 3225);
WIRE 16 -1 (-4775 3325)(-4775 3275);
WIRE 16 -1 (-4925 3275)(-4775 3275);
WIRE 16 -1 (-4775 3375)(-4775 3325);
WIRE 16 -1 (-4925 3325)(-4775 3325);
WIRE 16 -1 (-4775 3425)(-4775 3375);
WIRE 16 -1 (-4925 3375)(-4775 3375);
WIRE 16 -1 (-4775 3475)(-4775 3425);
WIRE 16 -1 (-4925 3425)(-4775 3425);
WIRE 16 -1 (-4775 3525)(-4775 3475);
WIRE 16 -1 (-4925 3475)(-4775 3475);
WIRE 16 -1 (-4775 3575)(-4775 3525);
WIRE 16 -1 (-4925 3525)(-4775 3525);
WIRE 16 -1 (-4775 3625)(-4775 3575);
WIRE 16 -1 (-4925 3575)(-4775 3575);
WIRE 16 -1 (-4925 3625)(-4775 3625);
WIRE 16 -1 (-3925 3125)(-3925 3175);
WIRE 16 -1 (-3925 3175)(-3925 3225);
WIRE 16 -1 (-3775 3175)(-3925 3175);
WIRE 16 -1 (-3925 3225)(-3925 3275);
WIRE 16 -1 (-3775 3225)(-3925 3225);
WIRE 16 -1 (-3925 3275)(-3925 3325);
WIRE 16 -1 (-3775 3275)(-3925 3275);
WIRE 16 -1 (-3925 3325)(-3925 3375);
WIRE 16 -1 (-3775 3325)(-3925 3325);
WIRE 16 -1 (-3925 3375)(-3925 3425);
WIRE 16 -1 (-3775 3375)(-3925 3375);
WIRE 16 -1 (-3925 3425)(-3925 3475);
WIRE 16 -1 (-3775 3425)(-3925 3425);
WIRE 16 -1 (-3925 3475)(-3925 3525);
WIRE 16 -1 (-3775 3475)(-3925 3475);
WIRE 16 -1 (-3925 3525)(-3925 3575);
WIRE 16 -1 (-3775 3525)(-3925 3525);
WIRE 16 -1 (-3925 3575)(-3925 3625);
WIRE 16 -1 (-3775 3575)(-3925 3575);
WIRE 16 -1 (-3775 3625)(-3925 3625);
WIRE 16 -1 (-6375 4050)(-6375 4100);
WIRE 16 -1 (-6375 4100)(-6375 4150);
WIRE 16 -1 (-6225 4100)(-6375 4100);
WIRE 16 -1 (-6375 4150)(-6375 4200);
WIRE 16 -1 (-6225 4150)(-6375 4150);
WIRE 16 -1 (-6375 4200)(-6375 4250);
WIRE 16 -1 (-6225 4200)(-6375 4200);
WIRE 16 -1 (-6375 4250)(-6375 4300);
WIRE 16 -1 (-6225 4250)(-6375 4250);
WIRE 16 -1 (-6375 4300)(-6375 4350);
WIRE 16 -1 (-6225 4300)(-6375 4300);
WIRE 16 -1 (-6375 4350)(-6375 4400);
WIRE 16 -1 (-6225 4350)(-6375 4350);
WIRE 16 -1 (-6375 4400)(-6375 4450);
WIRE 16 -1 (-6225 4400)(-6375 4400);
WIRE 16 -1 (-6375 4450)(-6375 4500);
WIRE 16 -1 (-6225 4450)(-6375 4450);
WIRE 16 -1 (-6375 4500)(-6375 4550);
WIRE 16 -1 (-6225 4500)(-6375 4500);
WIRE 16 -1 (-6225 4550)(-6375 4550);
WIRE 16 -1 (-6375 5000)(-6375 5050);
WIRE 16 -1 (-6375 5050)(-6375 5100);
WIRE 16 -1 (-6225 5050)(-6375 5050);
WIRE 16 -1 (-6375 5100)(-6375 5150);
WIRE 16 -1 (-6225 5100)(-6375 5100);
WIRE 16 -1 (-6375 5150)(-6375 5200);
WIRE 16 -1 (-6225 5150)(-6375 5150);
WIRE 16 -1 (-6375 5200)(-6375 5250);
WIRE 16 -1 (-6225 5200)(-6375 5200);
WIRE 16 -1 (-6375 5250)(-6375 5300);
WIRE 16 -1 (-6225 5250)(-6375 5250);
WIRE 16 -1 (-6375 5300)(-6375 5350);
WIRE 16 -1 (-6225 5300)(-6375 5300);
WIRE 16 -1 (-6375 5350)(-6375 5400);
WIRE 16 -1 (-6225 5350)(-6375 5350);
WIRE 16 -1 (-6375 5400)(-6375 5450);
WIRE 16 -1 (-6225 5400)(-6375 5400);
WIRE 16 -1 (-6375 5450)(-6375 5500);
WIRE 16 -1 (-6225 5450)(-6375 5450);
WIRE 16 -1 (-6225 5500)(-6375 5500);
WIRE 16 -1 (-4775 4075)(-4775 4125);
WIRE 16 -1 (-4775 4175)(-4775 4125);
WIRE 16 -1 (-4925 4125)(-4775 4125);
WIRE 16 -1 (-4775 4225)(-4775 4175);
WIRE 16 -1 (-4925 4175)(-4775 4175);
WIRE 16 -1 (-4775 4275)(-4775 4225);
WIRE 16 -1 (-4925 4225)(-4775 4225);
WIRE 16 -1 (-4775 4325)(-4775 4275);
WIRE 16 -1 (-4925 4275)(-4775 4275);
WIRE 16 -1 (-4775 4375)(-4775 4325);
WIRE 16 -1 (-4925 4325)(-4775 4325);
WIRE 16 -1 (-4775 4425)(-4775 4375);
WIRE 16 -1 (-4925 4375)(-4775 4375);
WIRE 16 -1 (-4775 4475)(-4775 4425);
WIRE 16 -1 (-4925 4425)(-4775 4425);
WIRE 16 -1 (-4775 4525)(-4775 4475);
WIRE 16 -1 (-4925 4475)(-4775 4475);
WIRE 16 -1 (-4775 4575)(-4775 4525);
WIRE 16 -1 (-4925 4525)(-4775 4525);
WIRE 16 -1 (-4925 4575)(-4775 4575);
WIRE 16 -1 (-3925 4075)(-3925 4125);
WIRE 16 -1 (-3925 4125)(-3925 4175);
WIRE 16 -1 (-3775 4125)(-3925 4125);
WIRE 16 -1 (-3925 4175)(-3925 4225);
WIRE 16 -1 (-3775 4175)(-3925 4175);
WIRE 16 -1 (-3925 4225)(-3925 4275);
WIRE 16 -1 (-3775 4225)(-3925 4225);
WIRE 16 -1 (-3925 4275)(-3925 4325);
WIRE 16 -1 (-3775 4275)(-3925 4275);
WIRE 16 -1 (-3925 4325)(-3925 4375);
WIRE 16 -1 (-3775 4325)(-3925 4325);
WIRE 16 -1 (-3925 4375)(-3925 4425);
WIRE 16 -1 (-3775 4375)(-3925 4375);
WIRE 16 -1 (-3925 4425)(-3925 4475);
WIRE 16 -1 (-3775 4425)(-3925 4425);
WIRE 16 -1 (-3925 4475)(-3925 4525);
WIRE 16 -1 (-3775 4475)(-3925 4475);
WIRE 16 -1 (-3925 4525)(-3925 4575);
WIRE 16 -1 (-3775 4525)(-3925 4525);
WIRE 16 -1 (-3775 4575)(-3925 4575);
WIRE 16 -1 (-4775 5025)(-4775 5075);
WIRE 16 -1 (-4775 5125)(-4775 5075);
WIRE 16 -1 (-4925 5075)(-4775 5075);
WIRE 16 -1 (-4775 5175)(-4775 5125);
WIRE 16 -1 (-4925 5125)(-4775 5125);
WIRE 16 -1 (-4775 5225)(-4775 5175);
WIRE 16 -1 (-4925 5175)(-4775 5175);
WIRE 16 -1 (-4775 5275)(-4775 5225);
WIRE 16 -1 (-4925 5225)(-4775 5225);
WIRE 16 -1 (-4775 5325)(-4775 5275);
WIRE 16 -1 (-4925 5275)(-4775 5275);
WIRE 16 -1 (-4775 5375)(-4775 5325);
WIRE 16 -1 (-4925 5325)(-4775 5325);
WIRE 16 -1 (-4775 5425)(-4775 5375);
WIRE 16 -1 (-4925 5375)(-4775 5375);
WIRE 16 -1 (-4775 5475)(-4775 5425);
WIRE 16 -1 (-4925 5425)(-4775 5425);
WIRE 16 -1 (-4775 5525)(-4775 5475);
WIRE 16 -1 (-4925 5475)(-4775 5475);
WIRE 16 -1 (-4925 5525)(-4775 5525);
WIRE 16 -1 (-7225 3100)(-7225 3150);
WIRE 16 -1 (-7225 3200)(-7225 3150);
WIRE 16 -1 (-7375 3150)(-7225 3150);
WIRE 16 -1 (-7225 3250)(-7225 3200);
WIRE 16 -1 (-7375 3200)(-7225 3200);
WIRE 16 -1 (-7225 3300)(-7225 3250);
WIRE 16 -1 (-7375 3250)(-7225 3250);
WIRE 16 -1 (-7225 3350)(-7225 3300);
WIRE 16 -1 (-7375 3300)(-7225 3300);
WIRE 16 -1 (-7225 3400)(-7225 3350);
WIRE 16 -1 (-7375 3350)(-7225 3350);
WIRE 16 -1 (-7225 3450)(-7225 3400);
WIRE 16 -1 (-7375 3400)(-7225 3400);
WIRE 16 -1 (-7225 3500)(-7225 3450);
WIRE 16 -1 (-7375 3450)(-7225 3450);
WIRE 16 -1 (-7225 3550)(-7225 3500);
WIRE 16 -1 (-7375 3500)(-7225 3500);
WIRE 16 -1 (-7225 3600)(-7225 3550);
WIRE 16 -1 (-7375 3550)(-7225 3550);
WIRE 16 -1 (-7375 3600)(-7225 3600);
WIRE 16 -1 (-3925 5025)(-3925 5075);
WIRE 16 -1 (-3925 5075)(-3925 5125);
WIRE 16 -1 (-3775 5075)(-3925 5075);
WIRE 16 -1 (-3925 5125)(-3925 5175);
WIRE 16 -1 (-3775 5125)(-3925 5125);
WIRE 16 -1 (-3925 5175)(-3925 5225);
WIRE 16 -1 (-3775 5175)(-3925 5175);
WIRE 16 -1 (-3925 5225)(-3925 5275);
WIRE 16 -1 (-3775 5225)(-3925 5225);
WIRE 16 -1 (-3925 5275)(-3925 5325);
WIRE 16 -1 (-3775 5275)(-3925 5275);
WIRE 16 -1 (-3925 5325)(-3925 5375);
WIRE 16 -1 (-3775 5325)(-3925 5325);
WIRE 16 -1 (-3925 5375)(-3925 5425);
WIRE 16 -1 (-3775 5375)(-3925 5375);
WIRE 16 -1 (-3925 5425)(-3925 5475);
WIRE 16 -1 (-3775 5425)(-3925 5425);
WIRE 16 -1 (-3925 5475)(-3925 5525);
WIRE 16 -1 (-3775 5475)(-3925 5475);
WIRE 16 -1 (-3775 5525)(-3925 5525);
WIRE 16 -1 (-7225 4050)(-7225 4100);
WIRE 16 -1 (-7225 4150)(-7225 4100);
WIRE 16 -1 (-7375 4100)(-7225 4100);
WIRE 16 -1 (-7225 4200)(-7225 4150);
WIRE 16 -1 (-7375 4150)(-7225 4150);
WIRE 16 -1 (-7225 4250)(-7225 4200);
WIRE 16 -1 (-7375 4200)(-7225 4200);
WIRE 16 -1 (-7225 4300)(-7225 4250);
WIRE 16 -1 (-7375 4250)(-7225 4250);
WIRE 16 -1 (-7225 4350)(-7225 4300);
WIRE 16 -1 (-7375 4300)(-7225 4300);
WIRE 16 -1 (-7225 4400)(-7225 4350);
WIRE 16 -1 (-7375 4350)(-7225 4350);
WIRE 16 -1 (-7225 4450)(-7225 4400);
WIRE 16 -1 (-7375 4400)(-7225 4400);
WIRE 16 -1 (-7225 4500)(-7225 4450);
WIRE 16 -1 (-7375 4450)(-7225 4450);
WIRE 16 -1 (-7225 4550)(-7225 4500);
WIRE 16 -1 (-7375 4500)(-7225 4500);
WIRE 16 -1 (-7375 4550)(-7225 4550);
WIRE 16 -1 (-7225 5000)(-7225 5050);
WIRE 16 -1 (-7225 5100)(-7225 5050);
WIRE 16 -1 (-7375 5050)(-7225 5050);
WIRE 16 -1 (-7225 5150)(-7225 5100);
WIRE 16 -1 (-7375 5100)(-7225 5100);
WIRE 16 -1 (-7225 5200)(-7225 5150);
WIRE 16 -1 (-7375 5150)(-7225 5150);
WIRE 16 -1 (-7225 5250)(-7225 5200);
WIRE 16 -1 (-7375 5200)(-7225 5200);
WIRE 16 -1 (-7225 5300)(-7225 5250);
WIRE 16 -1 (-7375 5250)(-7225 5250);
WIRE 16 -1 (-7225 5350)(-7225 5300);
WIRE 16 -1 (-7375 5300)(-7225 5300);
WIRE 16 -1 (-7225 5400)(-7225 5350);
WIRE 16 -1 (-7375 5350)(-7225 5350);
WIRE 16 -1 (-7225 5450)(-7225 5400);
WIRE 16 -1 (-7375 5400)(-7225 5400);
WIRE 16 -1 (-7225 5500)(-7225 5450);
WIRE 16 -1 (-7375 5450)(-7225 5450);
WIRE 16 -1 (-7375 5500)(-7225 5500);
WIRE 16 -1 (-6375 3100)(-6375 3150);
WIRE 16 -1 (-6375 3150)(-6375 3200);
WIRE 16 -1 (-6225 3150)(-6375 3150);
WIRE 16 -1 (-6375 3200)(-6375 3250);
WIRE 16 -1 (-6225 3200)(-6375 3200);
WIRE 16 -1 (-6375 3250)(-6375 3300);
WIRE 16 -1 (-6225 3250)(-6375 3250);
WIRE 16 -1 (-6375 3300)(-6375 3350);
WIRE 16 -1 (-6225 3300)(-6375 3300);
WIRE 16 -1 (-6375 3350)(-6375 3400);
WIRE 16 -1 (-6225 3350)(-6375 3350);
WIRE 16 -1 (-6375 3400)(-6375 3450);
WIRE 16 -1 (-6225 3400)(-6375 3400);
WIRE 16 -1 (-6375 3450)(-6375 3500);
WIRE 16 -1 (-6225 3450)(-6375 3450);
WIRE 16 -1 (-6375 3500)(-6375 3550);
WIRE 16 -1 (-6225 3500)(-6375 3500);
WIRE 16 -1 (-6375 3550)(-6375 3600);
WIRE 16 -1 (-6225 3550)(-6375 3550);
WIRE 16 -1 (-6225 3600)(-6375 3600);
WIRE 16 -1 (-7375 4650)(-6825 4650);
FORCEPROP 2 LAST SIG_NAME L3_85OHM_10INCH_DP
J 0
(-7210 4660);
DISPLAY 0.510638 (-7210 4660);
PAINT ORANGE (-7210 4660);
FORCEPROP 2 LASTPROP $XR0 258 
J 0
(-6795 4650);
DISPLAY 0.638298 (-6795 4650);
PAINT MONO (-6795 4650);
DISPLAY INVISIBLE (-6795 4650);
WIRE 16 -1 (-7375 4600)(-6825 4600);
FORCEPROP 2 LAST SIG_NAME L3_85OHM_10INCH_DN
J 0
(-7210 4610);
DISPLAY 0.510638 (-7210 4610);
PAINT ORANGE (-7210 4610);
FORCEPROP 2 LASTPROP $XR0 258 
J 0
(-6795 4600);
DISPLAY 0.638298 (-6795 4600);
PAINT MONO (-6795 4600);
DISPLAY INVISIBLE (-6795 4600);
WIRE 16 -1 (-7375 5550)(-6825 5550);
FORCEPROP 2 LAST SIG_NAME L1_85OHM_10INCH_DN
J 0
(-7210 5560);
DISPLAY 0.510638 (-7210 5560);
PAINT ORANGE (-7210 5560);
FORCEPROP 2 LASTPROP $XR0 258 
J 0
(-6795 5550);
DISPLAY 0.638298 (-6795 5550);
PAINT MONO (-6795 5550);
DISPLAY INVISIBLE (-6795 5550);
WIRE 16 -1 (-7375 3700)(-6825 3700);
FORCEPROP 2 LAST SIG_NAME L5_85OHM_10INCH_DP
J 0
(-7210 3710);
DISPLAY 0.510638 (-7210 3710);
PAINT ORANGE (-7210 3710);
FORCEPROP 2 LASTPROP $XR0 258 
J 0
(-6795 3700);
DISPLAY 0.638298 (-6795 3700);
PAINT MONO (-6795 3700);
DISPLAY INVISIBLE (-6795 3700);
WIRE 16 -1 (-7375 3650)(-6825 3650);
FORCEPROP 2 LAST SIG_NAME L5_85OHM_10INCH_DN
J 0
(-7210 3660);
DISPLAY 0.510638 (-7210 3660);
PAINT ORANGE (-7210 3660);
FORCEPROP 2 LASTPROP $XR0 258 
J 0
(-6795 3650);
DISPLAY 0.638298 (-6795 3650);
PAINT MONO (-6795 3650);
DISPLAY INVISIBLE (-6795 3650);
WIRE 16 -1 (-6775 3650)(-6225 3650);
FORCEPROP 2 LAST SIG_NAME L5_85OHM_10INCH_DP
J 0
(-6610 3660);
DISPLAY 0.510638 (-6610 3660);
PAINT ORANGE (-6610 3660);
FORCEPROP 2 LASTPROP $XR0 258 
J 0
(-7045 3650);
DISPLAY 0.638298 (-7045 3650);
PAINT MONO (-7045 3650);
DISPLAY INVISIBLE (-7045 3650);
WIRE 16 -1 (-6775 3700)(-6225 3700);
FORCEPROP 2 LAST SIG_NAME L5_85OHM_10INCH_DN
J 0
(-6610 3710);
DISPLAY 0.510638 (-6610 3710);
PAINT ORANGE (-6610 3710);
FORCEPROP 2 LASTPROP $XR0 258 
J 0
(-7045 3700);
DISPLAY 0.638298 (-7045 3700);
PAINT MONO (-7045 3700);
DISPLAY INVISIBLE (-7045 3700);
WIRE 16 -1 (-6775 4600)(-6225 4600);
FORCEPROP 2 LAST SIG_NAME L3_85OHM_10INCH_DP
J 0
(-6610 4610);
DISPLAY 0.510638 (-6610 4610);
PAINT ORANGE (-6610 4610);
FORCEPROP 2 LASTPROP $XR0 258 
J 0
(-7045 4600);
DISPLAY 0.638298 (-7045 4600);
PAINT MONO (-7045 4600);
DISPLAY INVISIBLE (-7045 4600);
WIRE 16 -1 (-6775 5550)(-6225 5550);
FORCEPROP 2 LAST SIG_NAME L1_85OHM_10INCH_DP
J 0
(-6610 5560);
DISPLAY 0.510638 (-6610 5560);
PAINT ORANGE (-6610 5560);
FORCEPROP 2 LASTPROP $XR0 258 
J 0
(-7045 5550);
DISPLAY 0.638298 (-7045 5550);
PAINT MONO (-7045 5550);
DISPLAY INVISIBLE (-7045 5550);
WIRE 16 -1 (-4925 5575)(-4375 5575);
FORCEPROP 2 LAST SIG_NAME L10_85OHM_10INCH_DN
J 0
(-4760 5585);
DISPLAY 0.510638 (-4760 5585);
PAINT ORANGE (-4760 5585);
FORCEPROP 2 LASTPROP $XR0 258 
J 0
(-4345 5575);
DISPLAY 0.638298 (-4345 5575);
PAINT MONO (-4345 5575);
DISPLAY INVISIBLE (-4345 5575);
WIRE 16 -1 (-4925 5625)(-4375 5625);
FORCEPROP 2 LAST SIG_NAME L10_85OHM_10INCH_DP
J 0
(-4760 5635);
DISPLAY 0.510638 (-4760 5635);
PAINT ORANGE (-4760 5635);
FORCEPROP 2 LASTPROP $XR0 258 
J 0
(-4345 5625);
DISPLAY 0.638298 (-4345 5625);
PAINT MONO (-4345 5625);
DISPLAY INVISIBLE (-4345 5625);
WIRE 16 -1 (-4925 4675)(-4375 4675);
FORCEPROP 2 LAST SIG_NAME L12_85OHM_10INCH_DP
J 0
(-4760 4685);
DISPLAY 0.510638 (-4760 4685);
PAINT ORANGE (-4760 4685);
FORCEPROP 2 LASTPROP $XR0 258 
J 0
(-4345 4675);
DISPLAY 0.638298 (-4345 4675);
PAINT MONO (-4345 4675);
DISPLAY INVISIBLE (-4345 4675);
WIRE 16 -1 (-4925 4625)(-4375 4625);
FORCEPROP 2 LAST SIG_NAME L12_85OHM_10INCH_DN
J 0
(-4760 4635);
DISPLAY 0.510638 (-4760 4635);
PAINT ORANGE (-4760 4635);
FORCEPROP 2 LASTPROP $XR0 258 
J 0
(-4345 4625);
DISPLAY 0.638298 (-4345 4625);
PAINT MONO (-4345 4625);
DISPLAY INVISIBLE (-4345 4625);
WIRE 16 -1 (-4925 3725)(-4375 3725);
FORCEPROP 2 LAST SIG_NAME L14_85OHM_10INCH_DP
J 0
(-4760 3735);
DISPLAY 0.510638 (-4760 3735);
PAINT ORANGE (-4760 3735);
FORCEPROP 2 LASTPROP $XR0 258 
J 0
(-4345 3725);
DISPLAY 0.638298 (-4345 3725);
PAINT MONO (-4345 3725);
DISPLAY INVISIBLE (-4345 3725);
WIRE 16 -1 (-4925 3675)(-4375 3675);
FORCEPROP 2 LAST SIG_NAME L14_85OHM_10INCH_DN
J 0
(-4760 3685);
DISPLAY 0.510638 (-4760 3685);
PAINT ORANGE (-4760 3685);
FORCEPROP 2 LASTPROP $XR0 258 
J 0
(-4345 3675);
DISPLAY 0.638298 (-4345 3675);
PAINT MONO (-4345 3675);
DISPLAY INVISIBLE (-4345 3675);
WIRE 16 -1 (-4325 4625)(-3775 4625);
FORCEPROP 2 LAST SIG_NAME L12_85OHM_10INCH_DP
J 0
(-4160 4635);
DISPLAY 0.510638 (-4160 4635);
PAINT ORANGE (-4160 4635);
FORCEPROP 2 LASTPROP $XR0 258 
J 0
(-4595 4625);
DISPLAY 0.638298 (-4595 4625);
PAINT MONO (-4595 4625);
DISPLAY INVISIBLE (-4595 4625);
WIRE 16 -1 (-4325 4675)(-3775 4675);
FORCEPROP 2 LAST SIG_NAME L12_85OHM_10INCH_DN
J 0
(-4160 4685);
DISPLAY 0.510638 (-4160 4685);
PAINT ORANGE (-4160 4685);
FORCEPROP 2 LASTPROP $XR0 258 
J 0
(-4595 4675);
DISPLAY 0.638298 (-4595 4675);
PAINT MONO (-4595 4675);
DISPLAY INVISIBLE (-4595 4675);
WIRE 16 -1 (-4325 3675)(-3775 3675);
FORCEPROP 2 LAST SIG_NAME L14_85OHM_10INCH_DP
J 0
(-4160 3685);
DISPLAY 0.510638 (-4160 3685);
PAINT ORANGE (-4160 3685);
FORCEPROP 2 LASTPROP $XR0 258 
J 0
(-4595 3675);
DISPLAY 0.638298 (-4595 3675);
PAINT MONO (-4595 3675);
DISPLAY INVISIBLE (-4595 3675);
WIRE 16 -1 (-4325 3725)(-3775 3725);
FORCEPROP 2 LAST SIG_NAME L14_85OHM_10INCH_DN
J 0
(-4160 3735);
DISPLAY 0.510638 (-4160 3735);
PAINT ORANGE (-4160 3735);
FORCEPROP 2 LASTPROP $XR0 258 
J 0
(-4595 3725);
DISPLAY 0.638298 (-4595 3725);
PAINT MONO (-4595 3725);
DISPLAY INVISIBLE (-4595 3725);
WIRE 16 -1 (-4325 5575)(-3775 5575);
FORCEPROP 2 LAST SIG_NAME L10_85OHM_10INCH_DP
J 0
(-4160 5585);
DISPLAY 0.510638 (-4160 5585);
PAINT ORANGE (-4160 5585);
FORCEPROP 2 LASTPROP $XR0 258 
J 0
(-4595 5575);
DISPLAY 0.638298 (-4595 5575);
PAINT MONO (-4595 5575);
DISPLAY INVISIBLE (-4595 5575);
WIRE 16 -1 (-4325 5625)(-3775 5625);
FORCEPROP 2 LAST SIG_NAME L10_85OHM_10INCH_DN
J 0
(-4160 5635);
DISPLAY 0.510638 (-4160 5635);
PAINT ORANGE (-4160 5635);
FORCEPROP 2 LASTPROP $XR0 258 
J 0
(-4595 5625);
DISPLAY 0.638298 (-4595 5625);
PAINT MONO (-4595 5625);
DISPLAY INVISIBLE (-4595 5625);
WIRE 16 -1 (-6775 5600)(-6225 5600);
FORCEPROP 2 LAST SIG_NAME L1_85OHM_10INCH_DN
J 0
(-6610 5610);
DISPLAY 0.510638 (-6610 5610);
PAINT ORANGE (-6610 5610);
FORCEPROP 2 LASTPROP $XR0 258 
J 0
(-7045 5600);
DISPLAY 0.638298 (-7045 5600);
PAINT MONO (-7045 5600);
DISPLAY INVISIBLE (-7045 5600);
WIRE 16 -1 (-6775 4650)(-6225 4650);
FORCEPROP 2 LAST SIG_NAME L3_85OHM_10INCH_DN
J 0
(-6610 4660);
DISPLAY 0.510638 (-6610 4660);
PAINT ORANGE (-6610 4660);
FORCEPROP 2 LASTPROP $XR0 258 
J 0
(-7045 4650);
DISPLAY 0.638298 (-7045 4650);
PAINT MONO (-7045 4650);
DISPLAY INVISIBLE (-7045 4650);
WIRE 16 -1 (-7375 5600)(-6825 5600);
FORCEPROP 2 LAST SIG_NAME L1_85OHM_10INCH_DP
J 0
(-7210 5610);
DISPLAY 0.510638 (-7210 5610);
PAINT ORANGE (-7210 5610);
FORCEPROP 2 LASTPROP $XR0 258 
J 0
(-6795 5600);
DISPLAY 0.638298 (-6795 5600);
PAINT MONO (-6795 5600);
DISPLAY INVISIBLE (-6795 5600);
DOT 1 (-7225 3150);
DOT 1 (-7225 3200);
DOT 1 (-7225 3250);
DOT 1 (-7225 3300);
DOT 1 (-7225 3350);
DOT 1 (-7225 3400);
DOT 1 (-7225 3450);
DOT 1 (-7225 3550);
DOT 1 (-7225 3500);
DOT 1 (-7225 4100);
DOT 1 (-7225 4150);
DOT 1 (-7225 4200);
DOT 1 (-7225 4250);
DOT 1 (-7225 4300);
DOT 1 (-7225 4350);
DOT 1 (-7225 4400);
DOT 1 (-7225 4450);
DOT 1 (-7225 4500);
DOT 1 (-7225 5050);
DOT 1 (-7225 5100);
DOT 1 (-7225 5150);
DOT 1 (-7225 5200);
DOT 1 (-7225 5250);
DOT 1 (-7225 5350);
DOT 1 (-7225 5300);
DOT 1 (-7225 5400);
DOT 1 (-7225 5450);
DOT 1 (-6375 3150);
DOT 1 (-6375 3200);
DOT 1 (-6375 3250);
DOT 1 (-6375 3300);
DOT 1 (-6375 3350);
DOT 1 (-6375 3400);
DOT 1 (-4775 3175);
DOT 1 (-4775 3275);
DOT 1 (-4775 3225);
DOT 1 (-4775 3325);
DOT 1 (-4775 3375);
DOT 1 (-4775 3425);
DOT 1 (-3925 3175);
DOT 1 (-3925 3275);
DOT 1 (-3925 3225);
DOT 1 (-3925 3325);
DOT 1 (-3925 3375);
DOT 1 (-3925 3425);
DOT 1 (-6375 3450);
DOT 1 (-6375 3500);
DOT 1 (-6375 3550);
DOT 1 (-6375 4150);
DOT 1 (-6375 4100);
DOT 1 (-6375 4200);
DOT 1 (-6375 4300);
DOT 1 (-6375 4250);
DOT 1 (-6375 4350);
DOT 1 (-6375 4400);
DOT 1 (-6375 4450);
DOT 1 (-6375 4500);
DOT 1 (-6375 5050);
DOT 1 (-6375 5100);
DOT 1 (-6375 5150);
DOT 1 (-6375 5200);
DOT 1 (-6375 5250);
DOT 1 (-6375 5300);
DOT 1 (-6375 5350);
DOT 1 (-6375 5400);
DOT 1 (-6375 5450);
DOT 1 (-4775 3475);
DOT 1 (-4775 3525);
DOT 1 (-4775 3575);
DOT 1 (-4775 4125);
DOT 1 (-4775 4175);
DOT 1 (-4775 4225);
DOT 1 (-4775 4275);
DOT 1 (-4775 4325);
DOT 1 (-4775 4375);
DOT 1 (-4775 4425);
DOT 1 (-3925 3525);
DOT 1 (-3925 3475);
DOT 1 (-3925 3575);
DOT 1 (-3925 4175);
DOT 1 (-3925 4125);
DOT 1 (-3925 4225);
DOT 1 (-3925 4275);
DOT 1 (-3925 4325);
DOT 1 (-3925 4425);
DOT 1 (-3925 4375);
DOT 1 (-3925 4475);
DOT 1 (-4775 4475);
DOT 1 (-4775 4525);
DOT 1 (-4775 5075);
DOT 1 (-4775 5125);
DOT 1 (-4775 5175);
DOT 1 (-4775 5225);
DOT 1 (-4775 5275);
DOT 1 (-4775 5375);
DOT 1 (-4775 5425);
DOT 1 (-4775 5475);
DOT 1 (-3925 4525);
DOT 1 (-3925 5075);
DOT 1 (-3925 5125);
DOT 1 (-3925 5175);
DOT 1 (-3925 5225);
DOT 1 (-3925 5325);
DOT 1 (-3925 5275);
DOT 1 (-3925 5375);
DOT 1 (-3925 5425);
DOT 1 (-3925 5475);
DOT 1 (-4775 5325);
FORCENOTE
TP FAB3-DVT ADD COUPON SYMBOLS 20161118
(-3100 1900) 0;
DISPLAY LEFT (-3100 1900);
DISPLAY 1.021277 (-3100 1900);
PAINT RED (-3100 1900);
QUIT
